FILE_TYPE = MACRO_DRAWING;
SET COLOR_WIRE YELLOW;
SET COLOR_PROP ORANGE;
SET COLOR_DOT WHITE;
SET COLOR_ARC YELLOW;
SET COLOR_BODY GREEN;
SET COLOR_NOTE PURPLE;
SET PROP_DISPLAY VALUE;
SET PAGE_NUMBER P81;
FORCEADD VCC_CORE..1
(-1525 1950);
FORCEPROP 3 LASTPIN (-1525 1900) SIG_NAME P1V8_STBY\g
J 0
(-1515 1910);
DISPLAY 0.659574 (-1515 1910);
PAINT MONO (-1515 1910);
DISPLAY INVISIBLE (-1515 1910);
FORCEPROP 1 LAST HDL_POWER P1V8_STBY
J 1
(-1525 2000);
DISPLAY 0.489362 (-1525 2000);
PAINT GREEN (-1525 2000);
FORCEPROP 1 LAST PATH I666
J 0
(-1475 1975);
DISPLAY 0.872340 (-1475 1975);
PAINT AQUA (-1475 1975);
DISPLAY INVISIBLE (-1475 1975);
FORCEPROP 2 LAST CDS_LIB pure_quanta_power
J 0
(-1525 1950);
DISPLAY INVISIBLE (-1525 1950);
FORCEADD UNIVERSAL_POWER..1
R 2
(-1550 1225);
FORCEPROP 3 LASTPIN (-1550 1175) SIG_NAME P3V3_STBY\g
J 0
(-1540 1185);
DISPLAY 0.659574 (-1540 1185);
PAINT MONO (-1540 1185);
DISPLAY INVISIBLE (-1540 1185);
FORCEPROP 1 LAST HDL_POWER P3V3_STBY
J 1
(-1550 1275);
DISPLAY 0.489362 (-1550 1275);
PAINT GREEN (-1550 1275);
FORCEPROP 1 LAST PATH I667
J 2
(-1600 1250);
DISPLAY 0.872340 (-1600 1250);
PAINT AQUA (-1600 1250);
DISPLAY INVISIBLE (-1600 1250);
FORCEPROP 2 LAST CDS_LIB pure_quanta_power
J 0
(-1550 1225);
DISPLAY INVISIBLE (-1550 1225);
FORCEADD VCC_CORE..1
(-3350 1900);
FORCEPROP 3 LASTPIN (-3350 1850) SIG_NAME P1V8_STBY\g
J 0
(-3340 1860);
DISPLAY 0.659574 (-3340 1860);
PAINT MONO (-3340 1860);
DISPLAY INVISIBLE (-3340 1860);
FORCEPROP 1 LAST HDL_POWER P1V8_STBY
J 1
(-3350 1950);
DISPLAY 0.489362 (-3350 1950);
PAINT GREEN (-3350 1950);
FORCEPROP 1 LAST PATH I668
J 0
(-3300 1925);
DISPLAY 0.872340 (-3300 1925);
PAINT AQUA (-3300 1925);
DISPLAY INVISIBLE (-3300 1925);
FORCEPROP 2 LAST CDS_LIB pure_quanta_power
J 0
(-3350 1900);
DISPLAY INVISIBLE (-3350 1900);
FORCEADD UNIVERSAL_POWER..1
R 2
(-3150 2650);
FORCEPROP 3 LASTPIN (-3150 2600) SIG_NAME P3V3_STBY\g
J 0
(-3140 2610);
DISPLAY 0.659574 (-3140 2610);
PAINT MONO (-3140 2610);
DISPLAY INVISIBLE (-3140 2610);
FORCEPROP 1 LAST HDL_POWER P3V3_STBY
J 1
(-3150 2700);
DISPLAY 0.489362 (-3150 2700);
PAINT GREEN (-3150 2700);
FORCEPROP 1 LAST PATH I669
J 2
(-3200 2675);
DISPLAY 0.872340 (-3200 2675);
PAINT AQUA (-3200 2675);
DISPLAY INVISIBLE (-3200 2675);
FORCEPROP 2 LAST CDS_LIB pure_quanta_power
J 0
(-3150 2650);
DISPLAY INVISIBLE (-3150 2650);
FORCEADD LCMXO3D9400HC5BG484C..5
(-2300 1575);
FORCEPROP 1 LAST LOCATION U18
J 0
(-2697 2866);
DISPLAY 0.489362 (-2697 2866);
PAINT SKYBLUE (-2697 2866);
FORCEPROP 0 LAST $SEC 5
J 0
(-2685 3005);
DISPLAY 0.680851 (-2685 3005);
PAINT MONO (-2685 3005);
DISPLAY INVISIBLE (-2685 3005);
FORCEPROP 0 LAST CDS_SEC 5
J 0
(-2685 3005);
DISPLAY 0.680851 (-2685 3005);
DISPLAY INVISIBLE (-2685 3005);
FORCEPROP 0 LASTPIN (-2850 2525) $PN K10
J 2
(-2860 2535);
DISPLAY 0.489362 (-2860 2535);
PAINT MONO (-2860 2535);
FORCEPROP 0 LASTPIN (-2850 2475) $PN K11
J 2
(-2860 2485);
DISPLAY 0.489362 (-2860 2485);
PAINT MONO (-2860 2485);
FORCEPROP 0 LASTPIN (-2850 2425) $PN K12
J 2
(-2860 2435);
DISPLAY 0.489362 (-2860 2435);
PAINT MONO (-2860 2435);
FORCEPROP 0 LASTPIN (-2850 2375) $PN K13
J 2
(-2860 2385);
DISPLAY 0.489362 (-2860 2385);
PAINT MONO (-2860 2385);
FORCEPROP 0 LASTPIN (-2850 2325) $PN L11
J 2
(-2860 2335);
DISPLAY 0.489362 (-2860 2335);
PAINT MONO (-2860 2335);
FORCEPROP 0 LASTPIN (-2850 2275) $PN L12
J 2
(-2860 2285);
DISPLAY 0.489362 (-2860 2285);
PAINT MONO (-2860 2285);
FORCEPROP 0 LASTPIN (-2850 2225) $PN M11
J 2
(-2860 2235);
DISPLAY 0.489362 (-2860 2235);
PAINT MONO (-2860 2235);
FORCEPROP 0 LASTPIN (-2850 2175) $PN M12
J 2
(-2860 2185);
DISPLAY 0.489362 (-2860 2185);
PAINT MONO (-2860 2185);
FORCEPROP 0 LASTPIN (-2850 2125) $PN N10
J 2
(-2860 2135);
DISPLAY 0.489362 (-2860 2135);
PAINT MONO (-2860 2135);
FORCEPROP 0 LASTPIN (-2850 2075) $PN N11
J 2
(-2860 2085);
DISPLAY 0.489362 (-2860 2085);
PAINT MONO (-2860 2085);
FORCEPROP 0 LASTPIN (-2850 2025) $PN N12
J 2
(-2860 2035);
DISPLAY 0.489362 (-2860 2035);
PAINT MONO (-2860 2035);
FORCEPROP 0 LASTPIN (-2850 1975) $PN N13
J 2
(-2860 1985);
DISPLAY 0.489362 (-2860 1985);
PAINT MONO (-2860 1985);
FORCEPROP 0 LASTPIN (-1750 1125) $PN C7
J 0
(-1740 1135);
DISPLAY 0.489362 (-1740 1135);
PAINT MONO (-1740 1135);
FORCEPROP 0 LASTPIN (-1750 1075) $PN C12
J 0
(-1740 1085);
DISPLAY 0.489362 (-1740 1085);
PAINT MONO (-1740 1085);
FORCEPROP 0 LASTPIN (-1750 1025) $PN C16
J 0
(-1740 1035);
DISPLAY 0.489362 (-1740 1035);
PAINT MONO (-1740 1035);
FORCEPROP 0 LASTPIN (-1750 975) $PN G10
J 0
(-1740 985);
DISPLAY 0.489362 (-1740 985);
PAINT MONO (-1740 985);
FORCEPROP 0 LASTPIN (-1750 925) $PN G13
J 0
(-1740 935);
DISPLAY 0.489362 (-1740 935);
PAINT MONO (-1740 935);
FORCEPROP 0 LASTPIN (-1750 875) $PN H9
J 0
(-1740 885);
DISPLAY 0.489362 (-1740 885);
PAINT MONO (-1740 885);
FORCEPROP 0 LASTPIN (-1750 825) $PN H11
J 0
(-1740 835);
DISPLAY 0.489362 (-1740 835);
PAINT MONO (-1740 835);
FORCEPROP 0 LASTPIN (-1750 775) $PN H12
J 0
(-1740 785);
DISPLAY 0.489362 (-1740 785);
PAINT MONO (-1740 785);
FORCEPROP 0 LASTPIN (-1750 725) $PN H14
J 0
(-1740 735);
DISPLAY 0.489362 (-1740 735);
PAINT MONO (-1740 735);
FORCEPROP 0 LASTPIN (-1750 1825) $PN F20
J 0
(-1740 1835);
DISPLAY 0.489362 (-1740 1835);
PAINT MONO (-1740 1835);
FORCEPROP 0 LASTPIN (-1750 1775) $PN J15
J 0
(-1740 1785);
DISPLAY 0.489362 (-1740 1785);
PAINT MONO (-1740 1785);
FORCEPROP 0 LASTPIN (-1750 1725) $PN K15
J 0
(-1740 1735);
DISPLAY 0.489362 (-1740 1735);
PAINT MONO (-1740 1735);
FORCEPROP 0 LASTPIN (-1750 1675) $PN L15
J 0
(-1740 1685);
DISPLAY 0.489362 (-1740 1685);
PAINT MONO (-1740 1685);
FORCEPROP 0 LASTPIN (-1750 1625) $PN M15
J 0
(-1740 1635);
DISPLAY 0.489362 (-1740 1635);
PAINT MONO (-1740 1635);
FORCEPROP 0 LASTPIN (-1750 1575) $PN M18
J 0
(-1740 1585);
DISPLAY 0.489362 (-1740 1585);
PAINT MONO (-1740 1585);
FORCEPROP 0 LASTPIN (-1750 1525) $PN N15
J 0
(-1740 1535);
DISPLAY 0.489362 (-1740 1535);
PAINT MONO (-1740 1535);
FORCEPROP 0 LASTPIN (-1750 1475) $PN P15
J 0
(-1740 1485);
DISPLAY 0.489362 (-1740 1485);
PAINT MONO (-1740 1485);
FORCEPROP 0 LASTPIN (-1750 1425) $PN V20
J 0
(-1740 1435);
DISPLAY 0.489362 (-1740 1435);
PAINT MONO (-1740 1435);
FORCEPROP 0 LASTPIN (-2850 1125) $PN R9
J 2
(-2860 1135);
DISPLAY 0.489362 (-2860 1135);
PAINT MONO (-2860 1135);
FORCEPROP 0 LASTPIN (-2850 1075) $PN R10
J 2
(-2860 1085);
DISPLAY 0.489362 (-2860 1085);
PAINT MONO (-2860 1085);
FORCEPROP 0 LASTPIN (-2850 1025) $PN R11
J 2
(-2860 1035);
DISPLAY 0.489362 (-2860 1035);
PAINT MONO (-2860 1035);
FORCEPROP 0 LASTPIN (-2850 975) $PN R12
J 2
(-2860 985);
DISPLAY 0.489362 (-2860 985);
PAINT MONO (-2860 985);
FORCEPROP 0 LASTPIN (-2850 925) $PN R13
J 2
(-2860 935);
DISPLAY 0.489362 (-2860 935);
PAINT MONO (-2860 935);
FORCEPROP 0 LASTPIN (-2850 875) $PN R14
J 2
(-2860 885);
DISPLAY 0.489362 (-2860 885);
PAINT MONO (-2860 885);
FORCEPROP 0 LASTPIN (-2850 825) $PN W7
J 2
(-2860 835);
DISPLAY 0.489362 (-2860 835);
PAINT MONO (-2860 835);
FORCEPROP 0 LASTPIN (-2850 775) $PN W11
J 2
(-2860 785);
DISPLAY 0.489362 (-2860 785);
PAINT MONO (-2860 785);
FORCEPROP 0 LASTPIN (-2850 725) $PN W16
J 2
(-2860 735);
DISPLAY 0.489362 (-2860 735);
PAINT MONO (-2860 735);
FORCEPROP 0 LASTPIN (-2850 1325) $PN N8
J 2
(-2860 1335);
DISPLAY 0.489362 (-2860 1335);
PAINT MONO (-2860 1335);
FORCEPROP 0 LASTPIN (-2850 1275) $PN P8
J 2
(-2860 1285);
DISPLAY 0.489362 (-2860 1285);
PAINT MONO (-2860 1285);
FORCEPROP 0 LASTPIN (-2850 1225) $PN V3
J 2
(-2860 1235);
DISPLAY 0.489362 (-2860 1235);
PAINT MONO (-2860 1235);
FORCEPROP 0 LASTPIN (-2850 1625) $PN L8
J 2
(-2860 1635);
DISPLAY 0.489362 (-2860 1635);
PAINT MONO (-2860 1635);
FORCEPROP 0 LASTPIN (-2850 1525) $PN M3
J 2
(-2860 1535);
DISPLAY 0.489362 (-2860 1535);
PAINT MONO (-2860 1535);
FORCEPROP 0 LASTPIN (-2850 1575) $PN M8
J 2
(-2860 1585);
DISPLAY 0.489362 (-2860 1585);
PAINT MONO (-2860 1585);
FORCEPROP 0 LASTPIN (-2850 1825) $PN F3
J 2
(-2860 1835);
DISPLAY 0.489362 (-2860 1835);
PAINT MONO (-2860 1835);
FORCEPROP 0 LASTPIN (-2850 1775) $PN J8
J 2
(-2860 1785);
DISPLAY 0.489362 (-2860 1785);
PAINT MONO (-2860 1785);
FORCEPROP 0 LASTPIN (-2850 1725) $PN K8
J 2
(-2860 1735);
DISPLAY 0.489362 (-2860 1735);
PAINT MONO (-2860 1735);
FORCEPROP 1 LAST PART_NUMBER AJ094000T05
J 0
(-2697 2719);
DISPLAY 0.489362 (-2697 2719);
PAINT SKYBLUE (-2697 2719);
FORCEPROP 1 LAST MATERIAL IC
J 0
(-2697 2592);
DISPLAY 0.489362 (-2697 2592);
PAINT SKYBLUE (-2697 2592);
FORCEPROP 2 LAST VALUE LCMXO3D-9400HC-5BG484C
J 0
(-2690 2910);
DISPLAY 0.489362 (-2690 2910);
PAINT SKYBLUE (-2690 2910);
FORCEPROP 2 LAST PART_TYPE SMLF
J 0
(-2690 2955);
DISPLAY 0.680851 (-2690 2955);
FORCEPROP 1 LAST PATH I670
J 0
(-2300 1575);
DISPLAY 0.723404 (-2300 1575);
PAINT GREEN (-2300 1575);
DISPLAY INVISIBLE (-2300 1575);
FORCEPROP 2 LAST CDS_LIB pure_quanta
J 0
(-2300 1575);
DISPLAY INVISIBLE (-2300 1575);
FORCEPROP 1 LAST CDS_LMAN_SYM_OUTLINE -400,1000,400,-1000
J 0
(-2300 1575);
DISPLAY 0.468085 (-2300 1575);
PAINT GREEN (-2300 1575);
DISPLAY INVISIBLE (-2300 1575);
FORCEPROP 1 LAST NEEDS_NO_SIZE TRUE
J 0
(-2300 1575);
DISPLAY 0.723404 (-2300 1575);
PAINT GREEN (-2300 1575);
DISPLAY INVISIBLE (-2300 1575);
FORCEADD UNIVERSAL_POWER..1
R 2
(-3650 1750);
FORCEPROP 3 LASTPIN (-3650 1700) SIG_NAME P3V3_STBY\g
J 0
(-3640 1710);
DISPLAY 0.659574 (-3640 1710);
PAINT MONO (-3640 1710);
DISPLAY INVISIBLE (-3640 1710);
FORCEPROP 1 LAST HDL_POWER P3V3_STBY
J 1
(-3650 1800);
DISPLAY 0.489362 (-3650 1800);
PAINT GREEN (-3650 1800);
FORCEPROP 1 LAST PATH I671
J 2
(-3700 1775);
DISPLAY 0.872340 (-3700 1775);
PAINT AQUA (-3700 1775);
DISPLAY INVISIBLE (-3700 1775);
FORCEPROP 2 LAST CDS_LIB pure_quanta_power
J 0
(-3650 1750);
DISPLAY INVISIBLE (-3650 1750);
FORCEADD OFFPAGE..2
(-2125 6125);
FORCEPROP 2 LAST $XR0 54 
J 0
(-1936 6125);
DISPLAY 0.638298 (-1936 6125);
PAINT MONO (-1936 6125);
FORCEPROP 2 LAST PATH I672
J 0
(-1925 6175);
DISPLAY 0.680851 (-1925 6175);
DISPLAY INVISIBLE (-1925 6175);
FORCEPROP 2 LAST CDS_LIB standard
J 0
(-2125 6125);
DISPLAY INVISIBLE (-2125 6125);
FORCEPROP 1 LAST OFFPAGE TRUE
J 0
(-1800 6000);
DISPLAY 0.872340 (-1800 6000);
PAINT GREEN (-1800 6000);
DISPLAY INVISIBLE (-1800 6000);
FORCEPROP 1 LAST COMMENT_BODY TRUE
J 0
(-2170 6030);
DISPLAY 0.872340 (-2170 6030);
PAINT GREEN (-2170 6030);
DISPLAY INVISIBLE (-2170 6030);
FORCEADD OFFPAGE..1
R 2
(-2125 6075);
FORCEPROP 2 LAST $XR0 200 
J 0
(-1939 6075);
DISPLAY 0.638298 (-1939 6075);
PAINT MONO (-1939 6075);
FORCEPROP 2 LAST PATH I673
J 0
(-1925 6125);
DISPLAY 0.680851 (-1925 6125);
DISPLAY INVISIBLE (-1925 6125);
FORCEPROP 2 LAST CDS_LIB standard
J 0
(-2125 6075);
DISPLAY INVISIBLE (-2125 6075);
FORCEPROP 1 LAST OFFPAGE TRUE
J 2
(-2450 5950);
DISPLAY 0.872340 (-2450 5950);
PAINT GREEN (-2450 5950);
DISPLAY INVISIBLE (-2450 5950);
FORCEPROP 1 LAST COMMENT_BODY TRUE
J 2
(-2250 5975);
DISPLAY 0.872340 (-2250 5975);
PAINT GREEN (-2250 5975);
DISPLAY INVISIBLE (-2250 5975);
FORCEADD OFFPAGE..1
R 2
(-2125 6175);
FORCEPROP 2 LAST $XR0 186 
J 0
(-1939 6175);
DISPLAY 0.638298 (-1939 6175);
PAINT MONO (-1939 6175);
FORCEPROP 2 LAST PATH I674
J 0
(-1925 6225);
DISPLAY 0.680851 (-1925 6225);
DISPLAY INVISIBLE (-1925 6225);
FORCEPROP 2 LAST CDS_LIB standard
J 2
(-2125 6175);
DISPLAY INVISIBLE (-2125 6175);
FORCEPROP 1 LAST OFFPAGE TRUE
J 2
(-2450 6050);
DISPLAY 0.872340 (-2450 6050);
PAINT GREEN (-2450 6050);
DISPLAY INVISIBLE (-2450 6050);
FORCEPROP 1 LAST COMMENT_BODY TRUE
J 2
(-2250 6075);
DISPLAY 0.872340 (-2250 6075);
PAINT GREEN (-2250 6075);
DISPLAY INVISIBLE (-2250 6075);
FORCEADD OFFPAGE..1
R 2
(-2125 5975);
FORCEPROP 2 LAST $XR0 27 
J 0
(-1939 5975);
DISPLAY 0.638298 (-1939 5975);
PAINT MONO (-1939 5975);
FORCEPROP 2 LAST PATH I675
J 0
(-1925 6025);
DISPLAY 0.680851 (-1925 6025);
DISPLAY INVISIBLE (-1925 6025);
FORCEPROP 2 LAST CDS_LIB standard
J 0
(-2125 5975);
DISPLAY INVISIBLE (-2125 5975);
FORCEPROP 1 LAST OFFPAGE TRUE
J 2
(-2450 5850);
DISPLAY 0.872340 (-2450 5850);
PAINT GREEN (-2450 5850);
DISPLAY INVISIBLE (-2450 5850);
FORCEPROP 1 LAST COMMENT_BODY TRUE
J 2
(-2250 5875);
DISPLAY 0.872340 (-2250 5875);
PAINT GREEN (-2250 5875);
DISPLAY INVISIBLE (-2250 5875);
FORCEADD OFFPAGE..1
R 2
(-2125 6025);
FORCEPROP 2 LAST $XR0 183 
J 0
(-1939 6025);
DISPLAY 0.638298 (-1939 6025);
PAINT MONO (-1939 6025);
FORCEPROP 2 LAST PATH I676
J 0
(-1925 6075);
DISPLAY 0.680851 (-1925 6075);
DISPLAY INVISIBLE (-1925 6075);
FORCEPROP 2 LAST CDS_LIB standard
J 2
(-2125 6025);
DISPLAY INVISIBLE (-2125 6025);
FORCEPROP 1 LAST OFFPAGE TRUE
J 2
(-2450 5900);
DISPLAY 0.872340 (-2450 5900);
PAINT GREEN (-2450 5900);
DISPLAY INVISIBLE (-2450 5900);
FORCEPROP 1 LAST COMMENT_BODY TRUE
J 2
(-2250 5925);
DISPLAY 0.872340 (-2250 5925);
PAINT GREEN (-2250 5925);
DISPLAY INVISIBLE (-2250 5925);
FORCEADD OFFPAGE..1
R 2
(-2125 5925);
FORCEPROP 2 LAST $XR1 129 
J 0
(-1819 5925);
DISPLAY 0.638298 (-1819 5925);
PAINT MONO (-1819 5925);
FORCEPROP 2 LAST $XR0 128 
J 0
(-1939 5925);
DISPLAY 0.638298 (-1939 5925);
PAINT MONO (-1939 5925);
FORCEPROP 2 LAST PATH I677
J 0
(-1800 5975);
DISPLAY 0.680851 (-1800 5975);
DISPLAY INVISIBLE (-1800 5975);
FORCEPROP 2 LAST CDS_LIB standard
J 0
(-2125 5925);
DISPLAY INVISIBLE (-2125 5925);
FORCEPROP 1 LAST OFFPAGE TRUE
J 2
(-2450 5800);
DISPLAY 0.872340 (-2450 5800);
PAINT GREEN (-2450 5800);
DISPLAY INVISIBLE (-2450 5800);
FORCEPROP 1 LAST COMMENT_BODY TRUE
J 2
(-2250 5825);
DISPLAY 0.872340 (-2250 5825);
PAINT GREEN (-2250 5825);
DISPLAY INVISIBLE (-2250 5825);
FORCEADD OFFPAGE..2
(-2125 5825);
FORCEPROP 2 LAST $XR0 27 
J 0
(-1936 5825);
DISPLAY 0.638298 (-1936 5825);
PAINT MONO (-1936 5825);
FORCEPROP 1 LAST COMMENT_BODY TRUE
J 0
(-2170 5730);
DISPLAY 0.872340 (-2170 5730);
PAINT GREEN (-2170 5730);
DISPLAY INVISIBLE (-2170 5730);
FORCEPROP 1 LAST OFFPAGE TRUE
J 0
(-1800 5700);
DISPLAY 0.872340 (-1800 5700);
PAINT GREEN (-1800 5700);
DISPLAY INVISIBLE (-1800 5700);
FORCEPROP 2 LAST PATH I678
J 0
(-1925 5875);
DISPLAY 0.680851 (-1925 5875);
DISPLAY INVISIBLE (-1925 5875);
FORCEPROP 2 LAST CDS_LIB standard
J 0
(-2125 5825);
DISPLAY INVISIBLE (-2125 5825);
FORCEADD OFFPAGE..1
R 2
(-2125 5725);
FORCEPROP 2 LAST $XR1 54 
J 0
(-1849 5725);
DISPLAY 0.638298 (-1849 5725);
PAINT MONO (-1849 5725);
FORCEPROP 2 LAST $XR0 27 
J 0
(-1939 5725);
DISPLAY 0.638298 (-1939 5725);
PAINT MONO (-1939 5725);
FORCEPROP 2 LAST PATH I679
J 0
(-1925 5775);
DISPLAY 0.680851 (-1925 5775);
DISPLAY INVISIBLE (-1925 5775);
FORCEPROP 2 LAST CDS_LIB standard
J 0
(-2125 5725);
DISPLAY INVISIBLE (-2125 5725);
FORCEPROP 1 LAST OFFPAGE TRUE
J 2
(-2450 5600);
DISPLAY 0.872340 (-2450 5600);
PAINT GREEN (-2450 5600);
DISPLAY INVISIBLE (-2450 5600);
FORCEPROP 1 LAST COMMENT_BODY TRUE
J 2
(-2250 5625);
DISPLAY 0.872340 (-2250 5625);
PAINT GREEN (-2250 5625);
DISPLAY INVISIBLE (-2250 5625);
FORCEADD OFFPAGE..1
R 2
(-2125 5675);
FORCEPROP 2 LAST $XR1 129 
J 0
(-1819 5675);
DISPLAY 0.638298 (-1819 5675);
PAINT MONO (-1819 5675);
FORCEPROP 2 LAST $XR0 128 
J 0
(-1939 5675);
DISPLAY 0.638298 (-1939 5675);
PAINT MONO (-1939 5675);
FORCEPROP 2 LAST PATH I680
J 0
(-1800 5725);
DISPLAY 0.680851 (-1800 5725);
DISPLAY INVISIBLE (-1800 5725);
FORCEPROP 2 LAST CDS_LIB standard
J 0
(-2125 5675);
DISPLAY INVISIBLE (-2125 5675);
FORCEPROP 1 LAST OFFPAGE TRUE
J 2
(-2450 5550);
DISPLAY 0.872340 (-2450 5550);
PAINT GREEN (-2450 5550);
DISPLAY INVISIBLE (-2450 5550);
FORCEPROP 1 LAST COMMENT_BODY TRUE
J 2
(-2250 5575);
DISPLAY 0.872340 (-2250 5575);
PAINT GREEN (-2250 5575);
DISPLAY INVISIBLE (-2250 5575);
FORCEADD OFFPAGE..2
(-2125 5625);
FORCEPROP 2 LAST $XR0 28 
J 0
(-1936 5625);
DISPLAY 0.638298 (-1936 5625);
PAINT MONO (-1936 5625);
FORCEPROP 1 LAST OFFPAGE TRUE
J 0
(-1800 5500);
DISPLAY 0.872340 (-1800 5500);
PAINT GREEN (-1800 5500);
DISPLAY INVISIBLE (-1800 5500);
FORCEPROP 1 LAST COMMENT_BODY TRUE
J 0
(-2170 5530);
DISPLAY 0.872340 (-2170 5530);
PAINT GREEN (-2170 5530);
DISPLAY INVISIBLE (-2170 5530);
FORCEPROP 2 LAST PATH I681
J 0
(-1925 5675);
DISPLAY 0.680851 (-1925 5675);
DISPLAY INVISIBLE (-1925 5675);
FORCEPROP 2 LAST CDS_LIB standard
J 0
(-2125 5625);
DISPLAY INVISIBLE (-2125 5625);
FORCEADD OFFPAGE..1
R 2
(-2300 4975);
FORCEPROP 2 LAST $XR0 169 
J 0
(-2114 4975);
DISPLAY 0.638298 (-2114 4975);
PAINT MONO (-2114 4975);
FORCEPROP 1 LAST COMMENT_BODY TRUE
J 2
(-2425 4875);
DISPLAY 0.872340 (-2425 4875);
PAINT GREEN (-2425 4875);
DISPLAY INVISIBLE (-2425 4875);
FORCEPROP 1 LAST OFFPAGE TRUE
J 2
(-2625 4850);
DISPLAY 0.872340 (-2625 4850);
PAINT GREEN (-2625 4850);
DISPLAY INVISIBLE (-2625 4850);
FORCEPROP 2 LAST CDS_LIB standard
J 0
(-2300 4975);
DISPLAY INVISIBLE (-2300 4975);
FORCEPROP 2 LAST PATH I692
J 0
(-2100 5025);
DISPLAY 0.680851 (-2100 5025);
DISPLAY INVISIBLE (-2100 5025);
FORCEADD OFFPAGE..2
(-2300 5025);
FORCEPROP 2 LAST $XR0 183 
J 0
(-2111 5025);
DISPLAY 0.638298 (-2111 5025);
PAINT MONO (-2111 5025);
FORCEPROP 1 LAST COMMENT_BODY TRUE
J 0
(-2345 4930);
DISPLAY 0.872340 (-2345 4930);
PAINT GREEN (-2345 4930);
DISPLAY INVISIBLE (-2345 4930);
FORCEPROP 1 LAST OFFPAGE TRUE
J 0
(-1975 4900);
DISPLAY 0.872340 (-1975 4900);
PAINT GREEN (-1975 4900);
DISPLAY INVISIBLE (-1975 4900);
FORCEPROP 2 LAST CDS_LIB standard
J 0
(-2300 5025);
DISPLAY INVISIBLE (-2300 5025);
FORCEPROP 2 LAST PATH I693
J 0
(-2100 5075);
DISPLAY 0.680851 (-2100 5075);
DISPLAY INVISIBLE (-2100 5075);
FORCEADD OFFPAGE..2
(-2300 5125);
FORCEPROP 2 LAST $XR0 193 
J 0
(-2111 5125);
DISPLAY 0.638298 (-2111 5125);
PAINT MONO (-2111 5125);
FORCEPROP 1 LAST COMMENT_BODY TRUE
J 0
(-2345 5030);
DISPLAY 0.872340 (-2345 5030);
PAINT GREEN (-2345 5030);
DISPLAY INVISIBLE (-2345 5030);
FORCEPROP 1 LAST OFFPAGE TRUE
J 0
(-1975 5000);
DISPLAY 0.872340 (-1975 5000);
PAINT GREEN (-1975 5000);
DISPLAY INVISIBLE (-1975 5000);
FORCEPROP 2 LAST CDS_LIB standard
J 0
(-2300 5125);
DISPLAY INVISIBLE (-2300 5125);
FORCEPROP 2 LAST PATH I694
J 0
(-2100 5175);
DISPLAY 0.680851 (-2100 5175);
DISPLAY INVISIBLE (-2100 5175);
FORCEADD OFFPAGE..1
R 2
(-2300 5075);
FORCEPROP 2 LAST $XR0 144 
J 0
(-2114 5075);
DISPLAY 0.638298 (-2114 5075);
PAINT MONO (-2114 5075);
FORCEPROP 2 LAST CDS_LIB standard
J 0
(-2300 5075);
DISPLAY INVISIBLE (-2300 5075);
FORCEPROP 1 LAST OFFPAGE TRUE
J 2
(-2625 4950);
DISPLAY 0.872340 (-2625 4950);
PAINT GREEN (-2625 4950);
DISPLAY INVISIBLE (-2625 4950);
FORCEPROP 1 LAST COMMENT_BODY TRUE
J 2
(-2425 4975);
DISPLAY 0.872340 (-2425 4975);
PAINT GREEN (-2425 4975);
DISPLAY INVISIBLE (-2425 4975);
FORCEPROP 2 LAST PATH I695
J 0
(-2100 5125);
DISPLAY 0.680851 (-2100 5125);
DISPLAY INVISIBLE (-2100 5125);
FORCEADD Q_RES..1
(-3225 6075);
FORCEPROP 1 LAST LOCATION R278
J 0
(-3100 6075);
DISPLAY 0.489362 (-3100 6075);
PAINT SKYBLUE (-3100 6075);
FORCEPROP 0 LAST $SEC 1
J 0
(-3100 6125);
DISPLAY 0.680851 (-3100 6125);
PAINT MONO (-3100 6125);
DISPLAY INVISIBLE (-3100 6125);
FORCEPROP 0 LAST CDS_SEC 1
J 0
(-3100 6125);
DISPLAY 1.021277 (-3100 6125);
DISPLAY INVISIBLE (-3100 6125);
FORCEPROP 1 LASTPIN (-3325 6075) $PN 1
J 0
(-3313 6087);
DISPLAY 0.489362 (-3313 6087);
PAINT MONO (-3313 6087);
FORCEPROP 1 LASTPIN (-3125 6075) $PN 2
J 0
(-3163 6087);
DISPLAY 0.489362 (-3163 6087);
PAINT MONO (-3163 6087);
FORCEPROP 1 LAST VALUE 0
J 2
(-3350 6075);
DISPLAY 0.489362 (-3350 6075);
PAINT SKYBLUE (-3350 6075);
FORCEPROP 2 LAST ROOM RST_CPU0_PLD_TO_DIMM
J 2
(-3200 6175);
DISPLAY 0.744681 (-3200 6175);
PAINT RED (-3200 6175);
DISPLAY INVISIBLE (-3200 6175);
FORCEPROP 1 LAST PACK_TYPE 0402LF
J 2
(-3050 6000);
DISPLAY 0.489362 (-3050 6000);
PAINT SKYBLUE (-3050 6000);
DISPLAY INVISIBLE (-3050 6000);
FORCEPROP 1 LAST PART_NUMBER CS00002JB38
J 2
(-3125 6125);
DISPLAY 0.489362 (-3125 6125);
PAINT SKYBLUE (-3125 6125);
DISPLAY INVISIBLE (-3125 6125);
FORCEPROP 1 LAST TOLERANCE 5%
J 0
(-3350 6050);
DISPLAY 0.489362 (-3350 6050);
PAINT SKYBLUE (-3350 6050);
DISPLAY INVISIBLE (-3350 6050);
FORCEPROP 1 LAST MATERIAL CHIP
J 2
(-3050 6050);
DISPLAY 0.489362 (-3050 6050);
PAINT SKYBLUE (-3050 6050);
DISPLAY INVISIBLE (-3050 6050);
FORCEPROP 1 LAST WATTAGE 1/16W
J 2
(-3300 6000);
DISPLAY 0.489362 (-3300 6000);
PAINT SKYBLUE (-3300 6000);
DISPLAY INVISIBLE (-3300 6000);
FORCEPROP 1 LAST PATH I696
J 0
(-3275 6225);
DISPLAY 0.978723 (-3275 6225);
PAINT WHITE (-3275 6225);
DISPLAY INVISIBLE (-3275 6225);
FORCEPROP 2 LAST BOM_COST MEM
J 2
(-3200 6225);
DISPLAY 0.744681 (-3200 6225);
PAINT WHITE (-3200 6225);
DISPLAY INVISIBLE (-3200 6225);
FORCEPROP 2 LAST CDS_LIB pure_quanta
J 2
(-3225 6075);
DISPLAY INVISIBLE (-3225 6075);
FORCEADD Q_RES..1
(-3225 6125);
FORCEPROP 1 LAST LOCATION R270
J 0
(-3100 6125);
DISPLAY 0.489362 (-3100 6125);
PAINT SKYBLUE (-3100 6125);
FORCEPROP 0 LAST $SEC 1
J 2
(-3100 6175);
DISPLAY 0.680851 (-3100 6175);
PAINT MONO (-3100 6175);
DISPLAY INVISIBLE (-3100 6175);
FORCEPROP 0 LAST CDS_SEC 1
J 2
(-3100 6175);
DISPLAY 1.021277 (-3100 6175);
DISPLAY INVISIBLE (-3100 6175);
FORCEPROP 1 LASTPIN (-3325 6125) $PN 1
J 0
(-3313 6137);
DISPLAY 0.489362 (-3313 6137);
PAINT MONO (-3313 6137);
FORCEPROP 1 LASTPIN (-3125 6125) $PN 2
J 0
(-3163 6137);
DISPLAY 0.489362 (-3163 6137);
PAINT MONO (-3163 6137);
FORCEPROP 1 LAST VALUE 33
J 2
(-3350 6125);
DISPLAY 0.489362 (-3350 6125);
PAINT SKYBLUE (-3350 6125);
FORCEPROP 2 LAST ROOM RST_CPU0_PLD_TO_DIMM
J 2
(-3200 6225);
DISPLAY 0.744681 (-3200 6225);
PAINT RED (-3200 6225);
DISPLAY INVISIBLE (-3200 6225);
FORCEPROP 1 LAST PACK_TYPE 0402LF
J 2
(-3050 6050);
DISPLAY 0.489362 (-3050 6050);
PAINT SKYBLUE (-3050 6050);
DISPLAY INVISIBLE (-3050 6050);
FORCEPROP 1 LAST PART_NUMBER CS03302JB29
J 2
(-3125 6175);
DISPLAY 0.489362 (-3125 6175);
PAINT SKYBLUE (-3125 6175);
DISPLAY INVISIBLE (-3125 6175);
FORCEPROP 1 LAST TOLERANCE 5%
J 0
(-3350 6100);
DISPLAY 0.489362 (-3350 6100);
PAINT SKYBLUE (-3350 6100);
DISPLAY INVISIBLE (-3350 6100);
FORCEPROP 1 LAST MATERIAL CHIP
J 2
(-3050 6100);
DISPLAY 0.489362 (-3050 6100);
PAINT SKYBLUE (-3050 6100);
DISPLAY INVISIBLE (-3050 6100);
FORCEPROP 1 LAST WATTAGE 1/16W
J 2
(-3300 6050);
DISPLAY 0.489362 (-3300 6050);
PAINT SKYBLUE (-3300 6050);
DISPLAY INVISIBLE (-3300 6050);
FORCEPROP 1 LAST PATH I697
J 0
(-3275 6275);
DISPLAY 0.978723 (-3275 6275);
PAINT WHITE (-3275 6275);
DISPLAY INVISIBLE (-3275 6275);
FORCEPROP 2 LAST CDS_LIB pure_quanta
J 2
(-3225 6125);
DISPLAY INVISIBLE (-3225 6125);
FORCEPROP 2 LAST BOM_COST MEM
J 2
(-3200 6275);
DISPLAY 0.744681 (-3200 6275);
PAINT WHITE (-3200 6275);
DISPLAY INVISIBLE (-3200 6275);
FORCEADD Q_RES..1
(-3225 6175);
FORCEPROP 1 LAST LOCATION R284
J 0
(-3100 6175);
DISPLAY 0.489362 (-3100 6175);
PAINT SKYBLUE (-3100 6175);
FORCEPROP 0 LAST $SEC 1
J 0
(-3100 6225);
DISPLAY 0.680851 (-3100 6225);
PAINT MONO (-3100 6225);
DISPLAY INVISIBLE (-3100 6225);
FORCEPROP 0 LAST CDS_SEC 1
J 0
(-3100 6225);
DISPLAY 1.021277 (-3100 6225);
DISPLAY INVISIBLE (-3100 6225);
FORCEPROP 1 LASTPIN (-3325 6175) $PN 1
J 0
(-3313 6187);
DISPLAY 0.489362 (-3313 6187);
PAINT MONO (-3313 6187);
FORCEPROP 1 LASTPIN (-3125 6175) $PN 2
J 0
(-3163 6187);
DISPLAY 0.489362 (-3163 6187);
PAINT MONO (-3163 6187);
FORCEPROP 1 LAST VALUE 0
J 2
(-3350 6175);
DISPLAY 0.489362 (-3350 6175);
PAINT SKYBLUE (-3350 6175);
FORCEPROP 2 LAST ROOM RST_CPU0_PLD_TO_DIMM
J 2
(-3200 6275);
DISPLAY 0.744681 (-3200 6275);
PAINT RED (-3200 6275);
DISPLAY INVISIBLE (-3200 6275);
FORCEPROP 1 LAST PACK_TYPE 0402LF
J 2
(-3050 6100);
DISPLAY 0.489362 (-3050 6100);
PAINT SKYBLUE (-3050 6100);
DISPLAY INVISIBLE (-3050 6100);
FORCEPROP 1 LAST PART_NUMBER CS00002JB38
J 2
(-3125 6225);
DISPLAY 0.489362 (-3125 6225);
PAINT SKYBLUE (-3125 6225);
DISPLAY INVISIBLE (-3125 6225);
FORCEPROP 1 LAST TOLERANCE 5%
J 0
(-3350 6150);
DISPLAY 0.489362 (-3350 6150);
PAINT SKYBLUE (-3350 6150);
DISPLAY INVISIBLE (-3350 6150);
FORCEPROP 1 LAST MATERIAL CHIP
J 2
(-3050 6150);
DISPLAY 0.489362 (-3050 6150);
PAINT SKYBLUE (-3050 6150);
DISPLAY INVISIBLE (-3050 6150);
FORCEPROP 1 LAST WATTAGE 1/16W
J 2
(-3300 6100);
DISPLAY 0.489362 (-3300 6100);
PAINT SKYBLUE (-3300 6100);
DISPLAY INVISIBLE (-3300 6100);
FORCEPROP 1 LAST PATH I698
J 0
(-3275 6325);
DISPLAY 0.978723 (-3275 6325);
PAINT WHITE (-3275 6325);
DISPLAY INVISIBLE (-3275 6325);
FORCEPROP 2 LAST CDS_LIB pure_quanta
J 2
(-3225 6175);
DISPLAY INVISIBLE (-3225 6175);
FORCEPROP 2 LAST BOM_COST MEM
J 2
(-3200 6325);
DISPLAY 0.744681 (-3200 6325);
PAINT WHITE (-3200 6325);
DISPLAY INVISIBLE (-3200 6325);
FORCEADD Q_RES..1
(-3225 6025);
FORCEPROP 1 LAST LOCATION R226
J 0
(-3100 6025);
DISPLAY 0.489362 (-3100 6025);
PAINT SKYBLUE (-3100 6025);
FORCEPROP 0 LAST $SEC 1
J 0
(-3100 6075);
DISPLAY 0.680851 (-3100 6075);
PAINT MONO (-3100 6075);
DISPLAY INVISIBLE (-3100 6075);
FORCEPROP 0 LAST CDS_SEC 1
J 0
(-3100 6075);
DISPLAY 1.021277 (-3100 6075);
DISPLAY INVISIBLE (-3100 6075);
FORCEPROP 1 LASTPIN (-3325 6025) $PN 1
J 0
(-3313 6037);
DISPLAY 0.489362 (-3313 6037);
PAINT MONO (-3313 6037);
FORCEPROP 1 LASTPIN (-3125 6025) $PN 2
J 0
(-3163 6037);
DISPLAY 0.489362 (-3163 6037);
PAINT MONO (-3163 6037);
FORCEPROP 1 LAST VALUE 0
J 2
(-3350 6025);
DISPLAY 0.489362 (-3350 6025);
PAINT SKYBLUE (-3350 6025);
FORCEPROP 2 LAST ROOM RST_CPU0_PLD_TO_DIMM
J 2
(-3200 6125);
DISPLAY 0.744681 (-3200 6125);
PAINT RED (-3200 6125);
DISPLAY INVISIBLE (-3200 6125);
FORCEPROP 1 LAST PACK_TYPE 0402LF
J 2
(-3050 5950);
DISPLAY 0.489362 (-3050 5950);
PAINT SKYBLUE (-3050 5950);
DISPLAY INVISIBLE (-3050 5950);
FORCEPROP 1 LAST PART_NUMBER CS00002JB38
J 2
(-3125 6075);
DISPLAY 0.489362 (-3125 6075);
PAINT SKYBLUE (-3125 6075);
DISPLAY INVISIBLE (-3125 6075);
FORCEPROP 1 LAST TOLERANCE 5%
J 0
(-3350 6000);
DISPLAY 0.489362 (-3350 6000);
PAINT SKYBLUE (-3350 6000);
DISPLAY INVISIBLE (-3350 6000);
FORCEPROP 1 LAST MATERIAL CHIP
J 2
(-3050 6000);
DISPLAY 0.489362 (-3050 6000);
PAINT SKYBLUE (-3050 6000);
DISPLAY INVISIBLE (-3050 6000);
FORCEPROP 1 LAST WATTAGE 1/16W
J 2
(-3300 5950);
DISPLAY 0.489362 (-3300 5950);
PAINT SKYBLUE (-3300 5950);
DISPLAY INVISIBLE (-3300 5950);
FORCEPROP 1 LAST PATH I699
J 0
(-3275 6175);
DISPLAY 0.978723 (-3275 6175);
PAINT WHITE (-3275 6175);
DISPLAY INVISIBLE (-3275 6175);
FORCEPROP 2 LAST BOM_COST MEM
J 2
(-3200 6175);
DISPLAY 0.744681 (-3200 6175);
PAINT WHITE (-3200 6175);
DISPLAY INVISIBLE (-3200 6175);
FORCEPROP 2 LAST CDS_LIB pure_quanta
J 2
(-3225 6025);
DISPLAY INVISIBLE (-3225 6025);
FORCEADD Q_RES..1
(-3225 5825);
FORCEPROP 1 LAST LOCATION R179
J 0
(-3100 5825);
DISPLAY 0.489362 (-3100 5825);
PAINT SKYBLUE (-3100 5825);
FORCEPROP 0 LAST $SEC 1
J 2
(-3100 5875);
DISPLAY 0.680851 (-3100 5875);
PAINT MONO (-3100 5875);
DISPLAY INVISIBLE (-3100 5875);
FORCEPROP 0 LAST CDS_SEC 1
J 2
(-3100 5875);
DISPLAY 1.021277 (-3100 5875);
DISPLAY INVISIBLE (-3100 5875);
FORCEPROP 1 LASTPIN (-3325 5825) $PN 1
J 0
(-3313 5837);
DISPLAY 0.489362 (-3313 5837);
PAINT MONO (-3313 5837);
FORCEPROP 1 LASTPIN (-3125 5825) $PN 2
J 0
(-3163 5837);
DISPLAY 0.489362 (-3163 5837);
PAINT MONO (-3163 5837);
FORCEPROP 1 LAST VALUE 33
J 2
(-3350 5825);
DISPLAY 0.489362 (-3350 5825);
PAINT SKYBLUE (-3350 5825);
FORCEPROP 2 LAST ROOM RST_CPU0_PLD_TO_DIMM
J 2
(-3200 5925);
DISPLAY 0.744681 (-3200 5925);
PAINT RED (-3200 5925);
DISPLAY INVISIBLE (-3200 5925);
FORCEPROP 1 LAST PACK_TYPE 0402LF
J 2
(-3050 5750);
DISPLAY 0.489362 (-3050 5750);
PAINT SKYBLUE (-3050 5750);
DISPLAY INVISIBLE (-3050 5750);
FORCEPROP 1 LAST PART_NUMBER CS03302JB29
J 2
(-3125 5875);
DISPLAY 0.489362 (-3125 5875);
PAINT SKYBLUE (-3125 5875);
DISPLAY INVISIBLE (-3125 5875);
FORCEPROP 1 LAST TOLERANCE 5%
J 0
(-3350 5800);
DISPLAY 0.489362 (-3350 5800);
PAINT SKYBLUE (-3350 5800);
DISPLAY INVISIBLE (-3350 5800);
FORCEPROP 1 LAST MATERIAL CHIP
J 2
(-3050 5800);
DISPLAY 0.489362 (-3050 5800);
PAINT SKYBLUE (-3050 5800);
DISPLAY INVISIBLE (-3050 5800);
FORCEPROP 1 LAST WATTAGE 1/16W
J 2
(-3300 5750);
DISPLAY 0.489362 (-3300 5750);
PAINT SKYBLUE (-3300 5750);
DISPLAY INVISIBLE (-3300 5750);
FORCEPROP 1 LAST PATH I700
J 0
(-3275 5975);
DISPLAY 0.978723 (-3275 5975);
PAINT WHITE (-3275 5975);
DISPLAY INVISIBLE (-3275 5975);
FORCEPROP 2 LAST CDS_LIB pure_quanta
J 2
(-3225 5825);
DISPLAY INVISIBLE (-3225 5825);
FORCEPROP 2 LAST BOM_COST MEM
J 2
(-3200 5975);
DISPLAY 0.744681 (-3200 5975);
PAINT WHITE (-3200 5975);
DISPLAY INVISIBLE (-3200 5975);
FORCEADD Q_RES..1
(-3225 5625);
FORCEPROP 1 LAST LOCATION R81
J 0
(-3100 5625);
DISPLAY 0.489362 (-3100 5625);
PAINT SKYBLUE (-3100 5625);
FORCEPROP 0 LAST $SEC 1
J 0
(-3100 5650);
DISPLAY 0.680851 (-3100 5650);
PAINT MONO (-3100 5650);
DISPLAY INVISIBLE (-3100 5650);
FORCEPROP 0 LAST CDS_SEC 1
J 0
(-3100 5650);
DISPLAY 0.680851 (-3100 5650);
DISPLAY INVISIBLE (-3100 5650);
FORCEPROP 1 LASTPIN (-3325 5625) $PN 1
J 0
(-3313 5637);
DISPLAY 0.489362 (-3313 5637);
PAINT MONO (-3313 5637);
FORCEPROP 1 LASTPIN (-3125 5625) $PN 2
J 0
(-3163 5637);
DISPLAY 0.489362 (-3163 5637);
PAINT MONO (-3163 5637);
FORCEPROP 1 LAST VALUE 33
J 2
(-3350 5625);
DISPLAY 0.489362 (-3350 5625);
PAINT SKYBLUE (-3350 5625);
FORCEPROP 2 LAST ROOM RST_CPU0_PLD_TO_DIMM
J 2
(-3200 5725);
DISPLAY 0.744681 (-3200 5725);
PAINT RED (-3200 5725);
DISPLAY INVISIBLE (-3200 5725);
FORCEPROP 1 LAST PACK_TYPE 0402LF
J 2
(-3050 5550);
DISPLAY 0.489362 (-3050 5550);
PAINT SKYBLUE (-3050 5550);
DISPLAY INVISIBLE (-3050 5550);
FORCEPROP 1 LAST PART_NUMBER CS03302JB29
J 2
(-3125 5675);
DISPLAY 0.489362 (-3125 5675);
PAINT SKYBLUE (-3125 5675);
DISPLAY INVISIBLE (-3125 5675);
FORCEPROP 1 LAST TOLERANCE 5%
J 0
(-3350 5600);
DISPLAY 0.489362 (-3350 5600);
PAINT SKYBLUE (-3350 5600);
DISPLAY INVISIBLE (-3350 5600);
FORCEPROP 1 LAST MATERIAL CHIP
J 2
(-3050 5600);
DISPLAY 0.489362 (-3050 5600);
PAINT SKYBLUE (-3050 5600);
DISPLAY INVISIBLE (-3050 5600);
FORCEPROP 1 LAST WATTAGE 1/16W
J 2
(-3300 5550);
DISPLAY 0.489362 (-3300 5550);
PAINT SKYBLUE (-3300 5550);
DISPLAY INVISIBLE (-3300 5550);
FORCEPROP 1 LAST PATH I701
J 0
(-3275 5775);
DISPLAY 0.978723 (-3275 5775);
PAINT WHITE (-3275 5775);
DISPLAY INVISIBLE (-3275 5775);
FORCEPROP 2 LAST BOM_COST MEM
J 2
(-3200 5775);
DISPLAY 0.744681 (-3200 5775);
PAINT WHITE (-3200 5775);
DISPLAY INVISIBLE (-3200 5775);
FORCEPROP 2 LAST CDS_LIB pure_quanta
J 0
(-3225 5625);
DISPLAY INVISIBLE (-3225 5625);
FORCEADD Q_RES..1
(-3175 5075);
FORCEPROP 1 LAST LOCATION R271
J 0
(-3050 5075);
DISPLAY 0.489362 (-3050 5075);
PAINT SKYBLUE (-3050 5075);
FORCEPROP 0 LAST $SEC 1
J 2
(-3050 5125);
DISPLAY 0.680851 (-3050 5125);
PAINT MONO (-3050 5125);
DISPLAY INVISIBLE (-3050 5125);
FORCEPROP 0 LAST CDS_SEC 1
J 2
(-3050 5125);
DISPLAY 1.021277 (-3050 5125);
DISPLAY INVISIBLE (-3050 5125);
FORCEPROP 1 LASTPIN (-3275 5075) $PN 1
J 0
(-3263 5087);
DISPLAY 0.489362 (-3263 5087);
PAINT MONO (-3263 5087);
FORCEPROP 1 LASTPIN (-3075 5075) $PN 2
J 0
(-3113 5087);
DISPLAY 0.489362 (-3113 5087);
PAINT MONO (-3113 5087);
FORCEPROP 1 LAST VALUE 0
J 2
(-3300 5075);
DISPLAY 0.489362 (-3300 5075);
PAINT SKYBLUE (-3300 5075);
FORCEPROP 2 LAST ROOM RST_CPU0_PLD_TO_DIMM
J 2
(-3150 5175);
DISPLAY 0.744681 (-3150 5175);
PAINT RED (-3150 5175);
DISPLAY INVISIBLE (-3150 5175);
FORCEPROP 1 LAST PACK_TYPE 0402LF
J 2
(-3000 5000);
DISPLAY 0.489362 (-3000 5000);
PAINT SKYBLUE (-3000 5000);
DISPLAY INVISIBLE (-3000 5000);
FORCEPROP 1 LAST PART_NUMBER CS00002JB38
J 2
(-3075 5125);
DISPLAY 0.489362 (-3075 5125);
PAINT SKYBLUE (-3075 5125);
DISPLAY INVISIBLE (-3075 5125);
FORCEPROP 1 LAST TOLERANCE 5%
J 0
(-3300 5050);
DISPLAY 0.489362 (-3300 5050);
PAINT SKYBLUE (-3300 5050);
DISPLAY INVISIBLE (-3300 5050);
FORCEPROP 1 LAST MATERIAL CHIP
J 2
(-3000 5050);
DISPLAY 0.489362 (-3000 5050);
PAINT SKYBLUE (-3000 5050);
DISPLAY INVISIBLE (-3000 5050);
FORCEPROP 1 LAST WATTAGE 1/16W
J 2
(-3250 5000);
DISPLAY 0.489362 (-3250 5000);
PAINT SKYBLUE (-3250 5000);
DISPLAY INVISIBLE (-3250 5000);
FORCEPROP 1 LAST PATH I702
J 0
(-3225 5225);
DISPLAY 0.978723 (-3225 5225);
PAINT WHITE (-3225 5225);
DISPLAY INVISIBLE (-3225 5225);
FORCEPROP 2 LAST CDS_LIB pure_quanta
J 2
(-3175 5075);
DISPLAY INVISIBLE (-3175 5075);
FORCEPROP 2 LAST BOM_COST MEM
J 2
(-3150 5225);
DISPLAY 0.744681 (-3150 5225);
PAINT WHITE (-3150 5225);
DISPLAY INVISIBLE (-3150 5225);
FORCEADD Q_RES..1
(-3175 5025);
FORCEPROP 1 LAST LOCATION R227
J 0
(-3050 5025);
DISPLAY 0.489362 (-3050 5025);
PAINT SKYBLUE (-3050 5025);
FORCEPROP 0 LAST $SEC 1
J 2
(-3050 5075);
DISPLAY 0.680851 (-3050 5075);
PAINT MONO (-3050 5075);
DISPLAY INVISIBLE (-3050 5075);
FORCEPROP 0 LAST CDS_SEC 1
J 2
(-3050 5075);
DISPLAY 1.021277 (-3050 5075);
DISPLAY INVISIBLE (-3050 5075);
FORCEPROP 1 LASTPIN (-3275 5025) $PN 1
J 0
(-3263 5037);
DISPLAY 0.489362 (-3263 5037);
PAINT MONO (-3263 5037);
FORCEPROP 1 LASTPIN (-3075 5025) $PN 2
J 0
(-3113 5037);
DISPLAY 0.489362 (-3113 5037);
PAINT MONO (-3113 5037);
FORCEPROP 1 LAST VALUE 33
J 2
(-3300 5025);
DISPLAY 0.489362 (-3300 5025);
PAINT SKYBLUE (-3300 5025);
FORCEPROP 2 LAST ROOM RST_CPU0_PLD_TO_DIMM
J 2
(-3150 5125);
DISPLAY 0.744681 (-3150 5125);
PAINT RED (-3150 5125);
DISPLAY INVISIBLE (-3150 5125);
FORCEPROP 1 LAST PACK_TYPE 0402LF
J 2
(-3000 4950);
DISPLAY 0.489362 (-3000 4950);
PAINT SKYBLUE (-3000 4950);
DISPLAY INVISIBLE (-3000 4950);
FORCEPROP 1 LAST PART_NUMBER CS03302JB29
J 2
(-3075 5075);
DISPLAY 0.489362 (-3075 5075);
PAINT SKYBLUE (-3075 5075);
DISPLAY INVISIBLE (-3075 5075);
FORCEPROP 1 LAST TOLERANCE 5%
J 0
(-3300 5000);
DISPLAY 0.489362 (-3300 5000);
PAINT SKYBLUE (-3300 5000);
DISPLAY INVISIBLE (-3300 5000);
FORCEPROP 1 LAST MATERIAL CHIP
J 2
(-3000 5000);
DISPLAY 0.489362 (-3000 5000);
PAINT SKYBLUE (-3000 5000);
DISPLAY INVISIBLE (-3000 5000);
FORCEPROP 1 LAST WATTAGE 1/16W
J 2
(-3250 4950);
DISPLAY 0.489362 (-3250 4950);
PAINT SKYBLUE (-3250 4950);
DISPLAY INVISIBLE (-3250 4950);
FORCEPROP 1 LAST PATH I703
J 0
(-3225 5175);
DISPLAY 0.978723 (-3225 5175);
PAINT WHITE (-3225 5175);
DISPLAY INVISIBLE (-3225 5175);
FORCEPROP 2 LAST CDS_LIB pure_quanta
J 2
(-3175 5025);
DISPLAY INVISIBLE (-3175 5025);
FORCEPROP 2 LAST BOM_COST MEM
J 2
(-3150 5175);
DISPLAY 0.744681 (-3150 5175);
PAINT WHITE (-3150 5175);
DISPLAY INVISIBLE (-3150 5175);
FORCEADD Q_RES..1
(-3175 5125);
FORCEPROP 1 LAST LOCATION R285
J 0
(-3050 5125);
DISPLAY 0.489362 (-3050 5125);
PAINT SKYBLUE (-3050 5125);
FORCEPROP 0 LAST $SEC 1
J 2
(-3050 5175);
DISPLAY 0.680851 (-3050 5175);
PAINT MONO (-3050 5175);
DISPLAY INVISIBLE (-3050 5175);
FORCEPROP 0 LAST CDS_SEC 1
J 2
(-3050 5175);
DISPLAY 1.021277 (-3050 5175);
DISPLAY INVISIBLE (-3050 5175);
FORCEPROP 1 LASTPIN (-3275 5125) $PN 1
J 0
(-3263 5137);
DISPLAY 0.489362 (-3263 5137);
PAINT MONO (-3263 5137);
FORCEPROP 1 LASTPIN (-3075 5125) $PN 2
J 0
(-3113 5137);
DISPLAY 0.489362 (-3113 5137);
PAINT MONO (-3113 5137);
FORCEPROP 1 LAST VALUE 33
J 2
(-3300 5125);
DISPLAY 0.489362 (-3300 5125);
PAINT SKYBLUE (-3300 5125);
FORCEPROP 2 LAST ROOM RST_CPU0_PLD_TO_DIMM
J 2
(-3150 5225);
DISPLAY 0.744681 (-3150 5225);
PAINT RED (-3150 5225);
DISPLAY INVISIBLE (-3150 5225);
FORCEPROP 1 LAST PACK_TYPE 0402LF
J 2
(-3000 5050);
DISPLAY 0.489362 (-3000 5050);
PAINT SKYBLUE (-3000 5050);
DISPLAY INVISIBLE (-3000 5050);
FORCEPROP 1 LAST PART_NUMBER CS03302JB29
J 2
(-3075 5175);
DISPLAY 0.489362 (-3075 5175);
PAINT SKYBLUE (-3075 5175);
DISPLAY INVISIBLE (-3075 5175);
FORCEPROP 1 LAST TOLERANCE 5%
J 0
(-3300 5100);
DISPLAY 0.489362 (-3300 5100);
PAINT SKYBLUE (-3300 5100);
DISPLAY INVISIBLE (-3300 5100);
FORCEPROP 1 LAST MATERIAL CHIP
J 2
(-3000 5100);
DISPLAY 0.489362 (-3000 5100);
PAINT SKYBLUE (-3000 5100);
DISPLAY INVISIBLE (-3000 5100);
FORCEPROP 1 LAST WATTAGE 1/16W
J 2
(-3250 5050);
DISPLAY 0.489362 (-3250 5050);
PAINT SKYBLUE (-3250 5050);
DISPLAY INVISIBLE (-3250 5050);
FORCEPROP 1 LAST PATH I704
J 0
(-3225 5275);
DISPLAY 0.978723 (-3225 5275);
PAINT WHITE (-3225 5275);
DISPLAY INVISIBLE (-3225 5275);
FORCEPROP 2 LAST BOM_COST MEM
J 2
(-3150 5275);
DISPLAY 0.744681 (-3150 5275);
PAINT WHITE (-3150 5275);
DISPLAY INVISIBLE (-3150 5275);
FORCEPROP 2 LAST CDS_LIB pure_quanta
J 2
(-3175 5125);
DISPLAY INVISIBLE (-3175 5125);
FORCEADD OFFPAGE..1
R 2
(-2300 4925);
FORCEPROP 2 LAST $XR0 169 
J 0
(-2114 4925);
DISPLAY 0.638298 (-2114 4925);
PAINT MONO (-2114 4925);
FORCEPROP 1 LAST COMMENT_BODY TRUE
J 2
(-2425 4825);
DISPLAY 0.872340 (-2425 4825);
PAINT GREEN (-2425 4825);
DISPLAY INVISIBLE (-2425 4825);
FORCEPROP 1 LAST OFFPAGE TRUE
J 2
(-2625 4800);
DISPLAY 0.872340 (-2625 4800);
PAINT GREEN (-2625 4800);
DISPLAY INVISIBLE (-2625 4800);
FORCEPROP 2 LAST CDS_LIB standard
J 0
(-2300 4925);
DISPLAY INVISIBLE (-2300 4925);
FORCEPROP 2 LAST PATH I705
J 0
(-2100 4975);
DISPLAY 0.680851 (-2100 4975);
DISPLAY INVISIBLE (-2100 4975);
FORCEADD OFFPAGE..1
R 2
(-2300 4675);
FORCEPROP 2 LAST $XR1 125 
J 0
(-2024 4675);
DISPLAY 0.638298 (-2024 4675);
PAINT MONO (-2024 4675);
FORCEPROP 2 LAST $XR0 82 
J 0
(-2114 4675);
DISPLAY 0.638298 (-2114 4675);
PAINT MONO (-2114 4675);
FORCEPROP 1 LAST COMMENT_BODY TRUE
J 2
(-2425 4575);
DISPLAY 0.872340 (-2425 4575);
PAINT GREEN (-2425 4575);
DISPLAY INVISIBLE (-2425 4575);
FORCEPROP 1 LAST OFFPAGE TRUE
J 2
(-2625 4550);
DISPLAY 0.872340 (-2625 4550);
PAINT GREEN (-2625 4550);
DISPLAY INVISIBLE (-2625 4550);
FORCEPROP 2 LAST CDS_LIB standard
J 0
(-2300 4675);
DISPLAY INVISIBLE (-2300 4675);
FORCEPROP 2 LAST PATH I707
J 0
(-2000 4725);
DISPLAY 0.680851 (-2000 4725);
DISPLAY INVISIBLE (-2000 4725);
FORCEADD OFFPAGE..1
R 2
(-2300 4775);
FORCEPROP 2 LAST $XR5 96 
J 0
(-1664 4775);
DISPLAY 0.638298 (-1664 4775);
PAINT MONO (-1664 4775);
FORCEPROP 2 LAST $XR4 95 
J 0
(-1754 4775);
DISPLAY 0.638298 (-1754 4775);
PAINT MONO (-1754 4775);
FORCEPROP 2 LAST $XR3 94 
J 0
(-1844 4775);
DISPLAY 0.638298 (-1844 4775);
PAINT MONO (-1844 4775);
FORCEPROP 2 LAST $XR2 93 
J 0
(-1934 4775);
DISPLAY 0.638298 (-1934 4775);
PAINT MONO (-1934 4775);
FORCEPROP 2 LAST $XR1 92 
J 0
(-2024 4775);
DISPLAY 0.638298 (-2024 4775);
PAINT MONO (-2024 4775);
FORCEPROP 2 LAST $XR0 91 
J 0
(-2114 4775);
DISPLAY 0.638298 (-2114 4775);
PAINT MONO (-2114 4775);
FORCEPROP 2 LAST CDS_LIB standard
J 0
(-2300 4775);
DISPLAY INVISIBLE (-2300 4775);
FORCEPROP 1 LAST OFFPAGE TRUE
J 2
(-2625 4650);
DISPLAY 0.872340 (-2625 4650);
PAINT GREEN (-2625 4650);
DISPLAY INVISIBLE (-2625 4650);
FORCEPROP 1 LAST COMMENT_BODY TRUE
J 2
(-2425 4675);
DISPLAY 0.872340 (-2425 4675);
PAINT GREEN (-2425 4675);
DISPLAY INVISIBLE (-2425 4675);
FORCEPROP 2 LAST PATH I708
J 0
(-1650 4825);
DISPLAY 0.680851 (-1650 4825);
DISPLAY INVISIBLE (-1650 4825);
FORCEADD OFFPAGE..1
R 2
(-2300 4825);
FORCEPROP 2 LAST $XR0 158 
J 0
(-2114 4825);
DISPLAY 0.638298 (-2114 4825);
PAINT MONO (-2114 4825);
FORCEPROP 1 LAST COMMENT_BODY TRUE
J 2
(-2425 4725);
DISPLAY 0.872340 (-2425 4725);
PAINT GREEN (-2425 4725);
DISPLAY INVISIBLE (-2425 4725);
FORCEPROP 1 LAST OFFPAGE TRUE
J 2
(-2625 4700);
DISPLAY 0.872340 (-2625 4700);
PAINT GREEN (-2625 4700);
DISPLAY INVISIBLE (-2625 4700);
FORCEPROP 2 LAST CDS_LIB standard
J 0
(-2300 4825);
DISPLAY INVISIBLE (-2300 4825);
FORCEPROP 2 LAST PATH I709
J 0
(-2100 4875);
DISPLAY 0.680851 (-2100 4875);
DISPLAY INVISIBLE (-2100 4875);
FORCEADD OFFPAGE..2
(-2300 4875);
FORCEPROP 2 LAST $XR0 169 
J 0
(-2111 4875);
DISPLAY 0.638298 (-2111 4875);
PAINT MONO (-2111 4875);
FORCEPROP 2 LAST CDS_LIB standard
J 0
(-2300 4875);
DISPLAY INVISIBLE (-2300 4875);
FORCEPROP 2 LAST PATH I710
J 0
(-2100 4925);
DISPLAY 0.680851 (-2100 4925);
DISPLAY INVISIBLE (-2100 4925);
FORCEPROP 1 LAST OFFPAGE TRUE
J 0
(-1975 4750);
DISPLAY 0.872340 (-1975 4750);
PAINT GREEN (-1975 4750);
DISPLAY INVISIBLE (-1975 4750);
FORCEPROP 1 LAST COMMENT_BODY TRUE
J 0
(-2345 4780);
DISPLAY 0.872340 (-2345 4780);
PAINT GREEN (-2345 4780);
DISPLAY INVISIBLE (-2345 4780);
FORCEADD OFFPAGE..1
R 2
(-2300 4425);
FORCEPROP 2 LAST $XR0 144 
J 0
(-2114 4425);
DISPLAY 0.638298 (-2114 4425);
PAINT MONO (-2114 4425);
FORCEPROP 1 LAST COMMENT_BODY TRUE
J 2
(-2425 4325);
DISPLAY 0.872340 (-2425 4325);
PAINT GREEN (-2425 4325);
DISPLAY INVISIBLE (-2425 4325);
FORCEPROP 1 LAST OFFPAGE TRUE
J 2
(-2625 4300);
DISPLAY 0.872340 (-2625 4300);
PAINT GREEN (-2625 4300);
DISPLAY INVISIBLE (-2625 4300);
FORCEPROP 2 LAST CDS_LIB standard
J 0
(-2300 4425);
DISPLAY INVISIBLE (-2300 4425);
FORCEPROP 2 LAST PATH I712
J 0
(-2100 4475);
DISPLAY 0.680851 (-2100 4475);
DISPLAY INVISIBLE (-2100 4475);
FORCEADD OFFPAGE..1
R 2
(-2300 4575);
FORCEPROP 2 LAST $XR5 90 
J 0
(-1664 4575);
DISPLAY 0.638298 (-1664 4575);
PAINT MONO (-1664 4575);
FORCEPROP 2 LAST $XR4 89 
J 0
(-1754 4575);
DISPLAY 0.638298 (-1754 4575);
PAINT MONO (-1754 4575);
FORCEPROP 2 LAST $XR3 88 
J 0
(-1844 4575);
DISPLAY 0.638298 (-1844 4575);
PAINT MONO (-1844 4575);
FORCEPROP 2 LAST $XR2 87 
J 0
(-1934 4575);
DISPLAY 0.638298 (-1934 4575);
PAINT MONO (-1934 4575);
FORCEPROP 2 LAST $XR1 86 
J 0
(-2024 4575);
DISPLAY 0.638298 (-2024 4575);
PAINT MONO (-2024 4575);
FORCEPROP 2 LAST $XR0 85 
J 0
(-2114 4575);
DISPLAY 0.638298 (-2114 4575);
PAINT MONO (-2114 4575);
FORCEPROP 2 LAST CDS_LIB standard
J 0
(-2300 4575);
DISPLAY INVISIBLE (-2300 4575);
FORCEPROP 1 LAST OFFPAGE TRUE
J 2
(-2625 4450);
DISPLAY 0.872340 (-2625 4450);
PAINT GREEN (-2625 4450);
DISPLAY INVISIBLE (-2625 4450);
FORCEPROP 1 LAST COMMENT_BODY TRUE
J 2
(-2425 4475);
DISPLAY 0.872340 (-2425 4475);
PAINT GREEN (-2425 4475);
DISPLAY INVISIBLE (-2425 4475);
FORCEPROP 2 LAST PATH I713
J 0
(-1650 4625);
DISPLAY 0.680851 (-1650 4625);
DISPLAY INVISIBLE (-1650 4625);
FORCEADD OFFPAGE..1
R 2
(-2300 4475);
FORCEPROP 2 LAST $XR1 124 
J 0
(-2024 4475);
DISPLAY 0.638298 (-2024 4475);
PAINT MONO (-2024 4475);
FORCEPROP 2 LAST $XR0 82 
J 0
(-2114 4475);
DISPLAY 0.638298 (-2114 4475);
PAINT MONO (-2114 4475);
FORCEPROP 2 LAST CDS_LIB standard
J 0
(-2300 4475);
DISPLAY INVISIBLE (-2300 4475);
FORCEPROP 1 LAST OFFPAGE TRUE
J 2
(-2625 4350);
DISPLAY 0.872340 (-2625 4350);
PAINT GREEN (-2625 4350);
DISPLAY INVISIBLE (-2625 4350);
FORCEPROP 1 LAST COMMENT_BODY TRUE
J 2
(-2425 4375);
DISPLAY 0.872340 (-2425 4375);
PAINT GREEN (-2425 4375);
DISPLAY INVISIBLE (-2425 4375);
FORCEPROP 2 LAST PATH I714
J 0
(-2000 4525);
DISPLAY 0.680851 (-2000 4525);
DISPLAY INVISIBLE (-2000 4525);
FORCEADD OFFPAGE..1
R 2
(-2300 4625);
FORCEPROP 2 LAST $XR0 209 
J 0
(-2114 4625);
DISPLAY 0.638298 (-2114 4625);
PAINT MONO (-2114 4625);
FORCEPROP 1 LAST COMMENT_BODY TRUE
J 2
(-2425 4525);
DISPLAY 0.872340 (-2425 4525);
PAINT GREEN (-2425 4525);
DISPLAY INVISIBLE (-2425 4525);
FORCEPROP 1 LAST OFFPAGE TRUE
J 2
(-2625 4500);
DISPLAY 0.872340 (-2625 4500);
PAINT GREEN (-2625 4500);
DISPLAY INVISIBLE (-2625 4500);
FORCEPROP 2 LAST CDS_LIB standard
J 0
(-2300 4625);
DISPLAY INVISIBLE (-2300 4625);
FORCEPROP 2 LAST PATH I715
J 0
(-2100 4675);
DISPLAY 0.680851 (-2100 4675);
DISPLAY INVISIBLE (-2100 4675);
FORCEADD OFFPAGE..1
R 2
(-2300 4375);
FORCEPROP 2 LAST $XR0 27 
J 0
(-2114 4375);
DISPLAY 0.638298 (-2114 4375);
PAINT MONO (-2114 4375);
FORCEPROP 1 LAST COMMENT_BODY TRUE
J 2
(-2425 4275);
DISPLAY 0.872340 (-2425 4275);
PAINT GREEN (-2425 4275);
DISPLAY INVISIBLE (-2425 4275);
FORCEPROP 1 LAST OFFPAGE TRUE
J 2
(-2625 4250);
DISPLAY 0.872340 (-2625 4250);
PAINT GREEN (-2625 4250);
DISPLAY INVISIBLE (-2625 4250);
FORCEPROP 2 LAST CDS_LIB standard
J 0
(-2300 4375);
DISPLAY INVISIBLE (-2300 4375);
FORCEPROP 2 LAST PATH I716
J 0
(-2100 4425);
DISPLAY 0.680851 (-2100 4425);
DISPLAY INVISIBLE (-2100 4425);
FORCEADD OFFPAGE..1
R 2
(-2300 3925);
FORCEPROP 2 LAST $XR1 186 
J 0
(-2024 3925);
DISPLAY 0.638298 (-2024 3925);
PAINT MONO (-2024 3925);
FORCEPROP 2 LAST $XR0 82 
J 0
(-2114 3925);
DISPLAY 0.638298 (-2114 3925);
PAINT MONO (-2114 3925);
FORCEPROP 1 LAST COMMENT_BODY TRUE
J 2
(-2425 3825);
DISPLAY 0.872340 (-2425 3825);
PAINT GREEN (-2425 3825);
DISPLAY INVISIBLE (-2425 3825);
FORCEPROP 1 LAST OFFPAGE TRUE
J 2
(-2625 3800);
DISPLAY 0.872340 (-2625 3800);
PAINT GREEN (-2625 3800);
DISPLAY INVISIBLE (-2625 3800);
FORCEPROP 2 LAST CDS_LIB standard
J 0
(-2300 3925);
DISPLAY INVISIBLE (-2300 3925);
FORCEPROP 2 LAST PATH I717
J 0
(-2000 3975);
DISPLAY 0.680851 (-2000 3975);
DISPLAY INVISIBLE (-2000 3975);
FORCEADD OFFPAGE..2
(-2300 3975);
FORCEPROP 2 LAST $XR2 123 
J 0
(-1871 3975);
DISPLAY 0.638298 (-1871 3975);
PAINT MONO (-1871 3975);
FORCEPROP 2 LAST $XR1 122 
J 0
(-1991 3975);
DISPLAY 0.638298 (-1991 3975);
PAINT MONO (-1991 3975);
FORCEPROP 2 LAST $XR0 119 
J 0
(-2111 3975);
DISPLAY 0.638298 (-2111 3975);
PAINT MONO (-2111 3975);
FORCEPROP 1 LAST COMMENT_BODY TRUE
J 0
(-2345 3880);
DISPLAY 0.872340 (-2345 3880);
PAINT GREEN (-2345 3880);
DISPLAY INVISIBLE (-2345 3880);
FORCEPROP 1 LAST OFFPAGE TRUE
J 0
(-1975 3850);
DISPLAY 0.872340 (-1975 3850);
PAINT GREEN (-1975 3850);
DISPLAY INVISIBLE (-1975 3850);
FORCEPROP 2 LAST CDS_LIB standard
J 0
(-2300 3975);
DISPLAY INVISIBLE (-2300 3975);
FORCEPROP 2 LAST PATH I718
J 0
(-1850 4025);
DISPLAY 0.680851 (-1850 4025);
DISPLAY INVISIBLE (-1850 4025);
FORCEADD OFFPAGE..1
R 2
(-2300 4075);
FORCEPROP 2 LAST $XR0 158 
J 0
(-2114 4075);
DISPLAY 0.638298 (-2114 4075);
PAINT MONO (-2114 4075);
FORCEPROP 1 LAST COMMENT_BODY TRUE
J 2
(-2425 3975);
DISPLAY 0.872340 (-2425 3975);
PAINT GREEN (-2425 3975);
DISPLAY INVISIBLE (-2425 3975);
FORCEPROP 1 LAST OFFPAGE TRUE
J 2
(-2625 3950);
DISPLAY 0.872340 (-2625 3950);
PAINT GREEN (-2625 3950);
DISPLAY INVISIBLE (-2625 3950);
FORCEPROP 2 LAST CDS_LIB standard
J 0
(-2300 4075);
DISPLAY INVISIBLE (-2300 4075);
FORCEPROP 2 LAST PATH I719
J 0
(-2100 4125);
DISPLAY 0.680851 (-2100 4125);
DISPLAY INVISIBLE (-2100 4125);
FORCEADD OFFPAGE..1
R 2
(-2300 4025);
FORCEPROP 2 LAST $XR1 200 
J 0
(-2024 4025);
DISPLAY 0.638298 (-2024 4025);
PAINT MONO (-2024 4025);
FORCEPROP 2 LAST $XR0 82 
J 0
(-2114 4025);
DISPLAY 0.638298 (-2114 4025);
PAINT MONO (-2114 4025);
FORCEPROP 1 LAST COMMENT_BODY TRUE
J 2
(-2425 3925);
DISPLAY 0.872340 (-2425 3925);
PAINT GREEN (-2425 3925);
DISPLAY INVISIBLE (-2425 3925);
FORCEPROP 1 LAST OFFPAGE TRUE
J 2
(-2625 3900);
DISPLAY 0.872340 (-2625 3900);
PAINT GREEN (-2625 3900);
DISPLAY INVISIBLE (-2625 3900);
FORCEPROP 2 LAST CDS_LIB standard
J 0
(-2300 4025);
DISPLAY INVISIBLE (-2300 4025);
FORCEPROP 2 LAST PATH I720
J 0
(-2000 4075);
DISPLAY 0.680851 (-2000 4075);
DISPLAY INVISIBLE (-2000 4075);
FORCEADD OFFPAGE..1
R 2
(-2300 3875);
FORCEPROP 2 LAST $XR1 128 
J 0
(-2024 3875);
DISPLAY 0.638298 (-2024 3875);
PAINT MONO (-2024 3875);
FORCEPROP 2 LAST $XR0 82 
J 0
(-2114 3875);
DISPLAY 0.638298 (-2114 3875);
PAINT MONO (-2114 3875);
FORCEPROP 1 LAST COMMENT_BODY TRUE
J 2
(-2425 3775);
DISPLAY 0.872340 (-2425 3775);
PAINT GREEN (-2425 3775);
DISPLAY INVISIBLE (-2425 3775);
FORCEPROP 1 LAST OFFPAGE TRUE
J 2
(-2625 3750);
DISPLAY 0.872340 (-2625 3750);
PAINT GREEN (-2625 3750);
DISPLAY INVISIBLE (-2625 3750);
FORCEPROP 2 LAST CDS_LIB standard
J 0
(-2300 3875);
DISPLAY INVISIBLE (-2300 3875);
FORCEPROP 2 LAST PATH I721
J 0
(-2000 3925);
DISPLAY 0.680851 (-2000 3925);
DISPLAY INVISIBLE (-2000 3925);
FORCEADD OFFPAGE..1
R 2
(-2300 3825);
FORCEPROP 2 LAST $XR1 128 
J 0
(-2024 3825);
DISPLAY 0.638298 (-2024 3825);
PAINT MONO (-2024 3825);
FORCEPROP 2 LAST $XR0 82 
J 0
(-2114 3825);
DISPLAY 0.638298 (-2114 3825);
PAINT MONO (-2114 3825);
FORCEPROP 1 LAST COMMENT_BODY TRUE
J 2
(-2425 3725);
DISPLAY 0.872340 (-2425 3725);
PAINT GREEN (-2425 3725);
DISPLAY INVISIBLE (-2425 3725);
FORCEPROP 1 LAST OFFPAGE TRUE
J 2
(-2625 3700);
DISPLAY 0.872340 (-2625 3700);
PAINT GREEN (-2625 3700);
DISPLAY INVISIBLE (-2625 3700);
FORCEPROP 2 LAST CDS_LIB standard
J 0
(-2300 3825);
DISPLAY INVISIBLE (-2300 3825);
FORCEPROP 2 LAST PATH I722
J 0
(-2000 3875);
DISPLAY 0.680851 (-2000 3875);
DISPLAY INVISIBLE (-2000 3875);
FORCEADD OFFPAGE..1
R 2
(-2300 3725);
FORCEPROP 2 LAST $XR0 119 
J 0
(-2114 3725);
DISPLAY 0.638298 (-2114 3725);
PAINT MONO (-2114 3725);
FORCEPROP 1 LAST COMMENT_BODY TRUE
J 2
(-2425 3625);
DISPLAY 0.872340 (-2425 3625);
PAINT GREEN (-2425 3625);
DISPLAY INVISIBLE (-2425 3625);
FORCEPROP 1 LAST OFFPAGE TRUE
J 2
(-2625 3600);
DISPLAY 0.872340 (-2625 3600);
PAINT GREEN (-2625 3600);
DISPLAY INVISIBLE (-2625 3600);
FORCEPROP 2 LAST CDS_LIB standard
J 0
(-2300 3725);
DISPLAY INVISIBLE (-2300 3725);
FORCEPROP 2 LAST PATH I723
J 0
(-2100 3775);
DISPLAY 0.680851 (-2100 3775);
DISPLAY INVISIBLE (-2100 3775);
FORCEADD OFFPAGE..2
(-2300 3775);
FORCEPROP 2 LAST $XR0 156 
J 0
(-2111 3775);
DISPLAY 0.638298 (-2111 3775);
PAINT MONO (-2111 3775);
FORCEPROP 1 LAST COMMENT_BODY TRUE
J 0
(-2345 3680);
DISPLAY 0.872340 (-2345 3680);
PAINT GREEN (-2345 3680);
DISPLAY INVISIBLE (-2345 3680);
FORCEPROP 1 LAST OFFPAGE TRUE
J 0
(-1975 3650);
DISPLAY 0.872340 (-1975 3650);
PAINT GREEN (-1975 3650);
DISPLAY INVISIBLE (-1975 3650);
FORCEPROP 2 LAST CDS_LIB standard
J 0
(-2300 3775);
DISPLAY INVISIBLE (-2300 3775);
FORCEPROP 2 LAST PATH I724
J 0
(-2100 3825);
DISPLAY 0.680851 (-2100 3825);
DISPLAY INVISIBLE (-2100 3825);
FORCEADD OFFPAGE..1
R 2
(-2300 3625);
FORCEPROP 2 LAST $XR0 27 
J 0
(-2114 3625);
DISPLAY 0.638298 (-2114 3625);
PAINT MONO (-2114 3625);
FORCEPROP 1 LAST COMMENT_BODY TRUE
J 2
(-2425 3525);
DISPLAY 0.872340 (-2425 3525);
PAINT GREEN (-2425 3525);
DISPLAY INVISIBLE (-2425 3525);
FORCEPROP 1 LAST OFFPAGE TRUE
J 2
(-2625 3500);
DISPLAY 0.872340 (-2625 3500);
PAINT GREEN (-2625 3500);
DISPLAY INVISIBLE (-2625 3500);
FORCEPROP 2 LAST CDS_LIB standard
J 0
(-2300 3625);
DISPLAY INVISIBLE (-2300 3625);
FORCEPROP 2 LAST PATH I725
J 0
(-2100 3675);
DISPLAY 0.680851 (-2100 3675);
DISPLAY INVISIBLE (-2100 3675);
FORCEADD OFFPAGE..2
(-2300 3525);
FORCEPROP 2 LAST $XR0 119 
J 0
(-2111 3525);
DISPLAY 0.638298 (-2111 3525);
PAINT MONO (-2111 3525);
FORCEPROP 1 LAST COMMENT_BODY TRUE
J 0
(-2345 3430);
DISPLAY 0.872340 (-2345 3430);
PAINT GREEN (-2345 3430);
DISPLAY INVISIBLE (-2345 3430);
FORCEPROP 1 LAST OFFPAGE TRUE
J 0
(-1975 3400);
DISPLAY 0.872340 (-1975 3400);
PAINT GREEN (-1975 3400);
DISPLAY INVISIBLE (-1975 3400);
FORCEPROP 2 LAST CDS_LIB standard
J 0
(-2300 3525);
DISPLAY INVISIBLE (-2300 3525);
FORCEPROP 2 LAST PATH I726
J 0
(-2100 3575);
DISPLAY 0.680851 (-2100 3575);
DISPLAY INVISIBLE (-2100 3575);
FORCEADD OFFPAGE..1
R 2
(-2300 3575);
FORCEPROP 2 LAST $XR0 27 
J 0
(-2114 3575);
DISPLAY 0.638298 (-2114 3575);
PAINT MONO (-2114 3575);
FORCEPROP 1 LAST COMMENT_BODY TRUE
J 2
(-2425 3475);
DISPLAY 0.872340 (-2425 3475);
PAINT GREEN (-2425 3475);
DISPLAY INVISIBLE (-2425 3475);
FORCEPROP 1 LAST OFFPAGE TRUE
J 2
(-2625 3450);
DISPLAY 0.872340 (-2625 3450);
PAINT GREEN (-2625 3450);
DISPLAY INVISIBLE (-2625 3450);
FORCEPROP 2 LAST CDS_LIB standard
J 0
(-2300 3575);
DISPLAY INVISIBLE (-2300 3575);
FORCEPROP 2 LAST PATH I727
J 0
(-2100 3625);
DISPLAY 0.680851 (-2100 3625);
DISPLAY INVISIBLE (-2100 3625);
FORCEADD Q_RES..1
(-3175 4425);
FORCEPROP 1 LAST LOCATION R182
J 0
(-3050 4425);
DISPLAY 0.489362 (-3050 4425);
PAINT SKYBLUE (-3050 4425);
FORCEPROP 0 LAST $SEC 1
J 2
(-3025 4475);
DISPLAY 0.680851 (-3025 4475);
PAINT MONO (-3025 4475);
DISPLAY INVISIBLE (-3025 4475);
FORCEPROP 0 LAST CDS_SEC 1
J 2
(-3025 4475);
DISPLAY 1.021277 (-3025 4475);
DISPLAY INVISIBLE (-3025 4475);
FORCEPROP 1 LASTPIN (-3275 4425) $PN 1
J 0
(-3263 4437);
DISPLAY 0.489362 (-3263 4437);
PAINT MONO (-3263 4437);
FORCEPROP 1 LASTPIN (-3075 4425) $PN 2
J 0
(-3113 4437);
DISPLAY 0.489362 (-3113 4437);
PAINT MONO (-3113 4437);
FORCEPROP 1 LAST VALUE 0
J 2
(-3300 4425);
DISPLAY 0.489362 (-3300 4425);
PAINT SKYBLUE (-3300 4425);
FORCEPROP 2 LAST ROOM RST_CPU0_PLD_TO_DIMM
J 2
(-3150 4525);
DISPLAY 0.744681 (-3150 4525);
PAINT RED (-3150 4525);
DISPLAY INVISIBLE (-3150 4525);
FORCEPROP 1 LAST PACK_TYPE 0402LF
J 2
(-3000 4350);
DISPLAY 0.489362 (-3000 4350);
PAINT SKYBLUE (-3000 4350);
DISPLAY INVISIBLE (-3000 4350);
FORCEPROP 1 LAST PART_NUMBER CS00002JB38
J 2
(-3075 4475);
DISPLAY 0.489362 (-3075 4475);
PAINT SKYBLUE (-3075 4475);
DISPLAY INVISIBLE (-3075 4475);
FORCEPROP 1 LAST TOLERANCE 5%
J 0
(-3300 4400);
DISPLAY 0.489362 (-3300 4400);
PAINT SKYBLUE (-3300 4400);
DISPLAY INVISIBLE (-3300 4400);
FORCEPROP 1 LAST MATERIAL CHIP
J 2
(-3000 4400);
DISPLAY 0.489362 (-3000 4400);
PAINT SKYBLUE (-3000 4400);
DISPLAY INVISIBLE (-3000 4400);
FORCEPROP 1 LAST WATTAGE 1/16W
J 2
(-3250 4350);
DISPLAY 0.489362 (-3250 4350);
PAINT SKYBLUE (-3250 4350);
DISPLAY INVISIBLE (-3250 4350);
FORCEPROP 1 LAST PATH I730
J 0
(-3225 4575);
DISPLAY 0.978723 (-3225 4575);
PAINT WHITE (-3225 4575);
DISPLAY INVISIBLE (-3225 4575);
FORCEPROP 2 LAST CDS_LIB pure_quanta
J 2
(-3175 4425);
DISPLAY INVISIBLE (-3175 4425);
FORCEPROP 2 LAST BOM_COST MEM
J 2
(-3150 4575);
DISPLAY 0.744681 (-3150 4575);
PAINT WHITE (-3150 4575);
DISPLAY INVISIBLE (-3150 4575);
FORCEADD Q_RES..1
(-3175 4375);
FORCEPROP 1 LAST LOCATION R223
J 0
(-3050 4375);
DISPLAY 0.489362 (-3050 4375);
PAINT SKYBLUE (-3050 4375);
FORCEPROP 0 LAST $SEC 1
J 0
(-3050 4425);
DISPLAY 0.680851 (-3050 4425);
PAINT MONO (-3050 4425);
DISPLAY INVISIBLE (-3050 4425);
FORCEPROP 0 LAST CDS_SEC 1
J 0
(-3050 4425);
DISPLAY 1.021277 (-3050 4425);
DISPLAY INVISIBLE (-3050 4425);
FORCEPROP 1 LASTPIN (-3275 4375) $PN 1
J 0
(-3263 4387);
DISPLAY 0.489362 (-3263 4387);
PAINT MONO (-3263 4387);
FORCEPROP 1 LASTPIN (-3075 4375) $PN 2
J 0
(-3113 4387);
DISPLAY 0.489362 (-3113 4387);
PAINT MONO (-3113 4387);
FORCEPROP 1 LAST VALUE 0
J 2
(-3300 4375);
DISPLAY 0.489362 (-3300 4375);
PAINT SKYBLUE (-3300 4375);
FORCEPROP 2 LAST ROOM RST_CPU0_PLD_TO_DIMM
J 2
(-3150 4475);
DISPLAY 0.744681 (-3150 4475);
PAINT RED (-3150 4475);
DISPLAY INVISIBLE (-3150 4475);
FORCEPROP 1 LAST PACK_TYPE 0402LF
J 2
(-3000 4300);
DISPLAY 0.489362 (-3000 4300);
PAINT SKYBLUE (-3000 4300);
DISPLAY INVISIBLE (-3000 4300);
FORCEPROP 1 LAST PART_NUMBER CS00002JB38
J 2
(-3075 4425);
DISPLAY 0.489362 (-3075 4425);
PAINT SKYBLUE (-3075 4425);
DISPLAY INVISIBLE (-3075 4425);
FORCEPROP 1 LAST TOLERANCE 5%
J 0
(-3300 4350);
DISPLAY 0.489362 (-3300 4350);
PAINT SKYBLUE (-3300 4350);
DISPLAY INVISIBLE (-3300 4350);
FORCEPROP 1 LAST MATERIAL CHIP
J 2
(-3000 4350);
DISPLAY 0.489362 (-3000 4350);
PAINT SKYBLUE (-3000 4350);
DISPLAY INVISIBLE (-3000 4350);
FORCEPROP 1 LAST WATTAGE 1/16W
J 2
(-3250 4300);
DISPLAY 0.489362 (-3250 4300);
PAINT SKYBLUE (-3250 4300);
DISPLAY INVISIBLE (-3250 4300);
FORCEPROP 1 LAST PATH I731
J 0
(-3225 4525);
DISPLAY 0.978723 (-3225 4525);
PAINT WHITE (-3225 4525);
DISPLAY INVISIBLE (-3225 4525);
FORCEPROP 2 LAST BOM_COST MEM
J 2
(-3150 4525);
DISPLAY 0.744681 (-3150 4525);
PAINT WHITE (-3150 4525);
DISPLAY INVISIBLE (-3150 4525);
FORCEPROP 2 LAST CDS_LIB pure_quanta
J 2
(-3175 4375);
DISPLAY INVISIBLE (-3175 4375);
FORCEADD Q_RES..1
R 2
(-3225 3975);
FORCEPROP 1 LAST LOCATION R958
J 2
(-3350 3975);
DISPLAY 0.489362 (-3350 3975);
PAINT SKYBLUE (-3350 3975);
FORCEPROP 0 LAST $SEC 1
J 2
(-3350 4000);
DISPLAY 0.680851 (-3350 4000);
PAINT MONO (-3350 4000);
DISPLAY INVISIBLE (-3350 4000);
FORCEPROP 0 LAST CDS_SEC 1
J 2
(-3350 4000);
DISPLAY 0.680851 (-3350 4000);
DISPLAY INVISIBLE (-3350 4000);
FORCEPROP 1 LASTPIN (-3125 3975) $PN 1
J 2
(-3137 3987);
DISPLAY 0.489362 (-3137 3987);
PAINT MONO (-3137 3987);
FORCEPROP 1 LASTPIN (-3325 3975) $PN 2
J 2
(-3287 3987);
DISPLAY 0.489362 (-3287 3987);
PAINT MONO (-3287 3987);
FORCEPROP 1 LAST VALUE 33
J 0
(-3100 3975);
DISPLAY 0.489362 (-3100 3975);
PAINT SKYBLUE (-3100 3975);
FORCEPROP 2 LAST ROOM RST_CPU0_PLD_TO_DIMM
J 0
(-3250 4075);
DISPLAY 0.744681 (-3250 4075);
PAINT RED (-3250 4075);
DISPLAY INVISIBLE (-3250 4075);
FORCEPROP 1 LAST PACK_TYPE 0402LF
J 0
(-3400 3900);
DISPLAY 0.489362 (-3400 3900);
PAINT SKYBLUE (-3400 3900);
DISPLAY INVISIBLE (-3400 3900);
FORCEPROP 1 LAST PART_NUMBER CS03302JB29
J 0
(-3325 4025);
DISPLAY 0.489362 (-3325 4025);
PAINT SKYBLUE (-3325 4025);
DISPLAY INVISIBLE (-3325 4025);
FORCEPROP 1 LAST TOLERANCE 5%
J 2
(-3100 3950);
DISPLAY 0.489362 (-3100 3950);
PAINT SKYBLUE (-3100 3950);
DISPLAY INVISIBLE (-3100 3950);
FORCEPROP 1 LAST MATERIAL CHIP
J 0
(-3400 3950);
DISPLAY 0.489362 (-3400 3950);
PAINT SKYBLUE (-3400 3950);
DISPLAY INVISIBLE (-3400 3950);
FORCEPROP 1 LAST WATTAGE 1/16W
J 0
(-3150 3900);
DISPLAY 0.489362 (-3150 3900);
PAINT SKYBLUE (-3150 3900);
DISPLAY INVISIBLE (-3150 3900);
FORCEPROP 1 LAST PATH I732
J 2
(-3175 4125);
DISPLAY 0.978723 (-3175 4125);
PAINT WHITE (-3175 4125);
DISPLAY INVISIBLE (-3175 4125);
FORCEPROP 2 LAST CDS_LIB pure_quanta
J 2
(-3225 3975);
DISPLAY INVISIBLE (-3225 3975);
FORCEPROP 2 LAST BOM_COST MEM
J 0
(-3250 4125);
DISPLAY 0.744681 (-3250 4125);
PAINT WHITE (-3250 4125);
DISPLAY INVISIBLE (-3250 4125);
FORCEADD Q_RES..1
R 2
(-3225 3775);
FORCEPROP 1 LAST LOCATION R275
J 2
(-3350 3775);
DISPLAY 0.489362 (-3350 3775);
PAINT SKYBLUE (-3350 3775);
FORCEPROP 0 LAST $SEC 1
J 0
(-3350 3825);
DISPLAY 0.680851 (-3350 3825);
PAINT MONO (-3350 3825);
DISPLAY INVISIBLE (-3350 3825);
FORCEPROP 0 LAST CDS_SEC 1
J 0
(-3350 3825);
DISPLAY 1.021277 (-3350 3825);
DISPLAY INVISIBLE (-3350 3825);
FORCEPROP 1 LASTPIN (-3125 3775) $PN 1
J 2
(-3137 3787);
DISPLAY 0.489362 (-3137 3787);
PAINT MONO (-3137 3787);
FORCEPROP 1 LASTPIN (-3325 3775) $PN 2
J 2
(-3287 3787);
DISPLAY 0.489362 (-3287 3787);
PAINT MONO (-3287 3787);
FORCEPROP 1 LAST VALUE 33
J 0
(-3100 3775);
DISPLAY 0.489362 (-3100 3775);
PAINT SKYBLUE (-3100 3775);
FORCEPROP 2 LAST ROOM RST_CPU0_PLD_TO_DIMM
J 0
(-3250 3875);
DISPLAY 0.744681 (-3250 3875);
PAINT RED (-3250 3875);
DISPLAY INVISIBLE (-3250 3875);
FORCEPROP 1 LAST PACK_TYPE 0402LF
J 0
(-3400 3700);
DISPLAY 0.489362 (-3400 3700);
PAINT SKYBLUE (-3400 3700);
DISPLAY INVISIBLE (-3400 3700);
FORCEPROP 1 LAST PART_NUMBER CS03302JB29
J 0
(-3325 3825);
DISPLAY 0.489362 (-3325 3825);
PAINT SKYBLUE (-3325 3825);
DISPLAY INVISIBLE (-3325 3825);
FORCEPROP 1 LAST TOLERANCE 5%
J 2
(-3100 3750);
DISPLAY 0.489362 (-3100 3750);
PAINT SKYBLUE (-3100 3750);
DISPLAY INVISIBLE (-3100 3750);
FORCEPROP 1 LAST MATERIAL CHIP
J 0
(-3400 3750);
DISPLAY 0.489362 (-3400 3750);
PAINT SKYBLUE (-3400 3750);
DISPLAY INVISIBLE (-3400 3750);
FORCEPROP 1 LAST WATTAGE 1/16W
J 0
(-3150 3700);
DISPLAY 0.489362 (-3150 3700);
PAINT SKYBLUE (-3150 3700);
DISPLAY INVISIBLE (-3150 3700);
FORCEPROP 1 LAST PATH I733
J 2
(-3175 3925);
DISPLAY 0.978723 (-3175 3925);
PAINT WHITE (-3175 3925);
DISPLAY INVISIBLE (-3175 3925);
FORCEPROP 2 LAST CDS_LIB pure_quanta
J 0
(-3225 3775);
DISPLAY INVISIBLE (-3225 3775);
FORCEPROP 2 LAST BOM_COST MEM
J 0
(-3250 3925);
DISPLAY 0.744681 (-3250 3925);
PAINT WHITE (-3250 3925);
DISPLAY INVISIBLE (-3250 3925);
FORCEADD Q_RES..1
R 2
(-3225 3625);
FORCEPROP 1 LAST LOCATION R183
J 2
(-3350 3625);
DISPLAY 0.489362 (-3350 3625);
PAINT SKYBLUE (-3350 3625);
FORCEPROP 0 LAST $SEC 1
J 0
(-3350 3675);
DISPLAY 0.680851 (-3350 3675);
PAINT MONO (-3350 3675);
DISPLAY INVISIBLE (-3350 3675);
FORCEPROP 0 LAST CDS_SEC 1
J 0
(-3350 3675);
DISPLAY 1.021277 (-3350 3675);
DISPLAY INVISIBLE (-3350 3675);
FORCEPROP 1 LASTPIN (-3125 3625) $PN 1
J 2
(-3137 3637);
DISPLAY 0.489362 (-3137 3637);
PAINT MONO (-3137 3637);
FORCEPROP 1 LASTPIN (-3325 3625) $PN 2
J 2
(-3287 3637);
DISPLAY 0.489362 (-3287 3637);
PAINT MONO (-3287 3637);
FORCEPROP 1 LAST VALUE 0
J 0
(-3100 3625);
DISPLAY 0.489362 (-3100 3625);
PAINT SKYBLUE (-3100 3625);
FORCEPROP 2 LAST ROOM RST_CPU0_PLD_TO_DIMM
J 0
(-3250 3725);
DISPLAY 0.744681 (-3250 3725);
PAINT RED (-3250 3725);
DISPLAY INVISIBLE (-3250 3725);
FORCEPROP 1 LAST PACK_TYPE 0402LF
J 0
(-3400 3550);
DISPLAY 0.489362 (-3400 3550);
PAINT SKYBLUE (-3400 3550);
DISPLAY INVISIBLE (-3400 3550);
FORCEPROP 1 LAST PART_NUMBER CS00002JB38
J 0
(-3325 3675);
DISPLAY 0.489362 (-3325 3675);
PAINT SKYBLUE (-3325 3675);
DISPLAY INVISIBLE (-3325 3675);
FORCEPROP 1 LAST TOLERANCE 5%
J 2
(-3100 3600);
DISPLAY 0.489362 (-3100 3600);
PAINT SKYBLUE (-3100 3600);
DISPLAY INVISIBLE (-3100 3600);
FORCEPROP 1 LAST MATERIAL CHIP
J 0
(-3400 3600);
DISPLAY 0.489362 (-3400 3600);
PAINT SKYBLUE (-3400 3600);
DISPLAY INVISIBLE (-3400 3600);
FORCEPROP 1 LAST WATTAGE 1/16W
J 0
(-3150 3550);
DISPLAY 0.489362 (-3150 3550);
PAINT SKYBLUE (-3150 3550);
DISPLAY INVISIBLE (-3150 3550);
FORCEPROP 1 LAST PATH I734
J 2
(-3175 3775);
DISPLAY 0.978723 (-3175 3775);
PAINT WHITE (-3175 3775);
DISPLAY INVISIBLE (-3175 3775);
FORCEPROP 2 LAST CDS_LIB pure_quanta
J 0
(-3225 3625);
DISPLAY INVISIBLE (-3225 3625);
FORCEPROP 2 LAST BOM_COST MEM
J 0
(-3250 3775);
DISPLAY 0.744681 (-3250 3775);
PAINT WHITE (-3250 3775);
DISPLAY INVISIBLE (-3250 3775);
FORCEADD Q_RES..1
R 2
(-3225 3575);
FORCEPROP 1 LAST LOCATION R185
J 2
(-3350 3575);
DISPLAY 0.489362 (-3350 3575);
PAINT SKYBLUE (-3350 3575);
FORCEPROP 0 LAST $SEC 1
J 0
(-3350 3625);
DISPLAY 0.680851 (-3350 3625);
PAINT MONO (-3350 3625);
DISPLAY INVISIBLE (-3350 3625);
FORCEPROP 0 LAST CDS_SEC 1
J 0
(-3350 3625);
DISPLAY 1.021277 (-3350 3625);
DISPLAY INVISIBLE (-3350 3625);
FORCEPROP 1 LASTPIN (-3125 3575) $PN 1
J 2
(-3137 3587);
DISPLAY 0.489362 (-3137 3587);
PAINT MONO (-3137 3587);
FORCEPROP 1 LASTPIN (-3325 3575) $PN 2
J 2
(-3287 3587);
DISPLAY 0.489362 (-3287 3587);
PAINT MONO (-3287 3587);
FORCEPROP 1 LAST VALUE 0
J 0
(-3100 3575);
DISPLAY 0.489362 (-3100 3575);
PAINT SKYBLUE (-3100 3575);
FORCEPROP 2 LAST ROOM RST_CPU0_PLD_TO_DIMM
J 0
(-3250 3675);
DISPLAY 0.744681 (-3250 3675);
PAINT RED (-3250 3675);
DISPLAY INVISIBLE (-3250 3675);
FORCEPROP 1 LAST PACK_TYPE 0402LF
J 0
(-3400 3500);
DISPLAY 0.489362 (-3400 3500);
PAINT SKYBLUE (-3400 3500);
DISPLAY INVISIBLE (-3400 3500);
FORCEPROP 1 LAST PART_NUMBER CS00002JB38
J 0
(-3325 3625);
DISPLAY 0.489362 (-3325 3625);
PAINT SKYBLUE (-3325 3625);
DISPLAY INVISIBLE (-3325 3625);
FORCEPROP 1 LAST TOLERANCE 5%
J 2
(-3100 3550);
DISPLAY 0.489362 (-3100 3550);
PAINT SKYBLUE (-3100 3550);
DISPLAY INVISIBLE (-3100 3550);
FORCEPROP 1 LAST MATERIAL CHIP
J 0
(-3400 3550);
DISPLAY 0.489362 (-3400 3550);
PAINT SKYBLUE (-3400 3550);
DISPLAY INVISIBLE (-3400 3550);
FORCEPROP 1 LAST WATTAGE 1/16W
J 0
(-3150 3500);
DISPLAY 0.489362 (-3150 3500);
PAINT SKYBLUE (-3150 3500);
DISPLAY INVISIBLE (-3150 3500);
FORCEPROP 1 LAST PATH I735
J 2
(-3175 3725);
DISPLAY 0.978723 (-3175 3725);
PAINT WHITE (-3175 3725);
DISPLAY INVISIBLE (-3175 3725);
FORCEPROP 2 LAST CDS_LIB pure_quanta
J 0
(-3225 3575);
DISPLAY INVISIBLE (-3225 3575);
FORCEPROP 2 LAST BOM_COST MEM
J 0
(-3250 3725);
DISPLAY 0.744681 (-3250 3725);
PAINT WHITE (-3250 3725);
DISPLAY INVISIBLE (-3250 3725);
FORCEADD Q_RES..1
R 2
(-3225 3525);
FORCEPROP 1 LAST LOCATION R959
J 2
(-3350 3525);
DISPLAY 0.489362 (-3350 3525);
PAINT SKYBLUE (-3350 3525);
FORCEPROP 0 LAST $SEC 1
J 2
(-3350 3550);
DISPLAY 0.680851 (-3350 3550);
PAINT MONO (-3350 3550);
DISPLAY INVISIBLE (-3350 3550);
FORCEPROP 0 LAST CDS_SEC 1
J 2
(-3350 3550);
DISPLAY 0.680851 (-3350 3550);
DISPLAY INVISIBLE (-3350 3550);
FORCEPROP 1 LASTPIN (-3125 3525) $PN 1
J 2
(-3137 3537);
DISPLAY 0.489362 (-3137 3537);
PAINT MONO (-3137 3537);
FORCEPROP 1 LASTPIN (-3325 3525) $PN 2
J 2
(-3287 3537);
DISPLAY 0.489362 (-3287 3537);
PAINT MONO (-3287 3537);
FORCEPROP 1 LAST VALUE 33
J 0
(-3100 3525);
DISPLAY 0.489362 (-3100 3525);
PAINT SKYBLUE (-3100 3525);
FORCEPROP 2 LAST ROOM RST_CPU0_PLD_TO_DIMM
J 0
(-3250 3625);
DISPLAY 0.744681 (-3250 3625);
PAINT RED (-3250 3625);
DISPLAY INVISIBLE (-3250 3625);
FORCEPROP 1 LAST PACK_TYPE 0402LF
J 0
(-3400 3450);
DISPLAY 0.489362 (-3400 3450);
PAINT SKYBLUE (-3400 3450);
DISPLAY INVISIBLE (-3400 3450);
FORCEPROP 1 LAST PART_NUMBER CS03302JB29
J 0
(-3325 3575);
DISPLAY 0.489362 (-3325 3575);
PAINT SKYBLUE (-3325 3575);
DISPLAY INVISIBLE (-3325 3575);
FORCEPROP 1 LAST TOLERANCE 5%
J 2
(-3100 3500);
DISPLAY 0.489362 (-3100 3500);
PAINT SKYBLUE (-3100 3500);
DISPLAY INVISIBLE (-3100 3500);
FORCEPROP 1 LAST MATERIAL CHIP
J 0
(-3400 3500);
DISPLAY 0.489362 (-3400 3500);
PAINT SKYBLUE (-3400 3500);
DISPLAY INVISIBLE (-3400 3500);
FORCEPROP 1 LAST WATTAGE 1/16W
J 0
(-3150 3450);
DISPLAY 0.489362 (-3150 3450);
PAINT SKYBLUE (-3150 3450);
DISPLAY INVISIBLE (-3150 3450);
FORCEPROP 1 LAST PATH I736
J 2
(-3175 3675);
DISPLAY 0.978723 (-3175 3675);
PAINT WHITE (-3175 3675);
DISPLAY INVISIBLE (-3175 3675);
FORCEPROP 2 LAST CDS_LIB pure_quanta
J 2
(-3225 3525);
DISPLAY INVISIBLE (-3225 3525);
FORCEPROP 2 LAST BOM_COST MEM
J 0
(-3250 3675);
DISPLAY 0.744681 (-3250 3675);
PAINT WHITE (-3250 3675);
DISPLAY INVISIBLE (-3250 3675);
FORCEADD LCMXO3D9400HC5BG484C..1
(-4825 4825);
FORCEPROP 1 LAST LOCATION U18
J 0
(-5326 6512);
DISPLAY 0.489362 (-5326 6512);
PAINT SKYBLUE (-5326 6512);
FORCEPROP 0 LAST $SEC 1
J 0
(-5315 6645);
DISPLAY 0.680851 (-5315 6645);
PAINT MONO (-5315 6645);
DISPLAY INVISIBLE (-5315 6645);
FORCEPROP 0 LAST CDS_SEC 1
J 0
(-5315 6645);
DISPLAY 0.680851 (-5315 6645);
DISPLAY INVISIBLE (-5315 6645);
FORCEPROP 0 LASTPIN (-5475 6175) $PN D3
J 2
(-5485 6185);
DISPLAY 0.489362 (-5485 6185);
PAINT MONO (-5485 6185);
FORCEPROP 0 LASTPIN (-5475 6125) $PN D4
J 2
(-5485 6135);
DISPLAY 0.489362 (-5485 6135);
PAINT MONO (-5485 6135);
FORCEPROP 0 LASTPIN (-5475 6075) $PN F6
J 2
(-5485 6085);
DISPLAY 0.489362 (-5485 6085);
PAINT MONO (-5485 6085);
FORCEPROP 0 LASTPIN (-5475 6025) $PN G7
J 2
(-5485 6035);
DISPLAY 0.489362 (-5485 6035);
PAINT MONO (-5485 6035);
FORCEPROP 0 LASTPIN (-5475 5975) $PN E4
J 2
(-5485 5985);
DISPLAY 0.489362 (-5485 5985);
PAINT MONO (-5485 5985);
FORCEPROP 0 LASTPIN (-5475 5925) $PN F5
J 2
(-5485 5935);
DISPLAY 0.489362 (-5485 5935);
PAINT MONO (-5485 5935);
FORCEPROP 0 LASTPIN (-5475 5875) $PN G6
J 2
(-5485 5885);
DISPLAY 0.489362 (-5485 5885);
PAINT MONO (-5485 5885);
FORCEPROP 0 LASTPIN (-5475 5825) $PN H7
J 2
(-5485 5835);
DISPLAY 0.489362 (-5485 5835);
PAINT MONO (-5485 5835);
FORCEPROP 0 LASTPIN (-5475 5775) $PN C1
J 2
(-5485 5785);
DISPLAY 0.489362 (-5485 5785);
PAINT MONO (-5485 5785);
FORCEPROP 0 LASTPIN (-5475 5725) $PN D2
J 2
(-5485 5735);
DISPLAY 0.489362 (-5485 5735);
PAINT MONO (-5485 5735);
FORCEPROP 0 LASTPIN (-5475 5675) $PN G5
J 2
(-5485 5685);
DISPLAY 0.489362 (-5485 5685);
PAINT MONO (-5485 5685);
FORCEPROP 0 LASTPIN (-5475 5625) $PN H6
J 2
(-5485 5635);
DISPLAY 0.489362 (-5485 5635);
PAINT MONO (-5485 5635);
FORCEPROP 0 LASTPIN (-5475 5575) $PN D1
J 2
(-5485 5585);
DISPLAY 0.489362 (-5485 5585);
PAINT MONO (-5485 5585);
FORCEPROP 0 LASTPIN (-5475 5525) $PN E2
J 2
(-5485 5535);
DISPLAY 0.489362 (-5485 5535);
PAINT MONO (-5485 5535);
FORCEPROP 0 LASTPIN (-5475 5475) $PN E3
J 2
(-5485 5485);
DISPLAY 0.489362 (-5485 5485);
PAINT MONO (-5485 5485);
FORCEPROP 0 LASTPIN (-5475 5425) $PN F4
J 2
(-5485 5435);
DISPLAY 0.489362 (-5485 5435);
PAINT MONO (-5485 5435);
FORCEPROP 0 LASTPIN (-5475 5375) $PN E1
J 2
(-5485 5385);
DISPLAY 0.489362 (-5485 5385);
PAINT MONO (-5485 5385);
FORCEPROP 0 LASTPIN (-5475 5325) $PN F1
J 2
(-5485 5335);
DISPLAY 0.489362 (-5485 5335);
PAINT MONO (-5485 5335);
FORCEPROP 0 LASTPIN (-5475 5275) $PN G3
J 2
(-5485 5285);
DISPLAY 0.489362 (-5485 5285);
PAINT MONO (-5485 5285);
FORCEPROP 0 LASTPIN (-5475 5225) $PN G4
J 2
(-5485 5235);
DISPLAY 0.489362 (-5485 5235);
PAINT MONO (-5485 5235);
FORCEPROP 0 LASTPIN (-4175 6175) $PN G2
J 0
(-4165 6185);
DISPLAY 0.489362 (-4165 6185);
PAINT MONO (-4165 6185);
FORCEPROP 0 LASTPIN (-4175 6125) $PN G1
J 0
(-4165 6135);
DISPLAY 0.489362 (-4165 6135);
PAINT MONO (-4165 6135);
FORCEPROP 0 LASTPIN (-4175 6075) $PN H4
J 0
(-4165 6085);
DISPLAY 0.489362 (-4165 6085);
PAINT MONO (-4165 6085);
FORCEPROP 0 LASTPIN (-4175 6025) $PN H3
J 0
(-4165 6035);
DISPLAY 0.489362 (-4165 6035);
PAINT MONO (-4165 6035);
FORCEPROP 0 LASTPIN (-4175 5975) $PN H2
J 0
(-4165 5985);
DISPLAY 0.489362 (-4165 5985);
PAINT MONO (-4165 5985);
FORCEPROP 0 LASTPIN (-4175 5925) $PN H1
J 0
(-4165 5935);
DISPLAY 0.489362 (-4165 5935);
PAINT MONO (-4165 5935);
FORCEPROP 0 LASTPIN (-4175 5875) $PN J7
J 0
(-4165 5885);
DISPLAY 0.489362 (-4165 5885);
PAINT MONO (-4165 5885);
FORCEPROP 0 LASTPIN (-4175 5825) $PN J6
J 0
(-4165 5835);
DISPLAY 0.489362 (-4165 5835);
PAINT MONO (-4165 5835);
FORCEPROP 0 LASTPIN (-4175 5775) $PN H5
J 0
(-4165 5785);
DISPLAY 0.489362 (-4165 5785);
PAINT MONO (-4165 5785);
FORCEPROP 0 LASTPIN (-4175 5725) $PN J5
J 0
(-4165 5735);
DISPLAY 0.489362 (-4165 5735);
PAINT MONO (-4165 5735);
FORCEPROP 0 LASTPIN (-4175 5675) $PN J4
J 0
(-4165 5685);
DISPLAY 0.489362 (-4165 5685);
PAINT MONO (-4165 5685);
FORCEPROP 0 LASTPIN (-4175 5625) $PN J3
J 0
(-4165 5635);
DISPLAY 0.489362 (-4165 5635);
PAINT MONO (-4165 5635);
FORCEPROP 0 LASTPIN (-4175 5575) $PN J2
J 0
(-4165 5585);
DISPLAY 0.489362 (-4165 5585);
PAINT MONO (-4165 5585);
FORCEPROP 0 LASTPIN (-4175 5525) $PN J1
J 0
(-4165 5535);
DISPLAY 0.489362 (-4165 5535);
PAINT MONO (-4165 5535);
FORCEPROP 0 LASTPIN (-4175 5475) $PN K7
J 0
(-4165 5485);
DISPLAY 0.489362 (-4165 5485);
PAINT MONO (-4165 5485);
FORCEPROP 0 LASTPIN (-4175 5425) $PN K6
J 0
(-4165 5435);
DISPLAY 0.489362 (-4165 5435);
PAINT MONO (-4165 5435);
FORCEPROP 0 LASTPIN (-5475 4075) $PN L7
J 2
(-5485 4085);
DISPLAY 0.489362 (-5485 4085);
PAINT MONO (-5485 4085);
FORCEPROP 0 LASTPIN (-5475 4025) $PN K5
J 2
(-5485 4035);
DISPLAY 0.489362 (-5485 4035);
PAINT MONO (-5485 4035);
FORCEPROP 0 LASTPIN (-5475 3975) $PN K4
J 2
(-5485 3985);
DISPLAY 0.489362 (-5485 3985);
PAINT MONO (-5485 3985);
FORCEPROP 0 LASTPIN (-5475 3925) $PN K3
J 2
(-5485 3935);
DISPLAY 0.489362 (-5485 3935);
PAINT MONO (-5485 3935);
FORCEPROP 0 LASTPIN (-5475 3875) $PN K2
J 2
(-5485 3885);
DISPLAY 0.489362 (-5485 3885);
PAINT MONO (-5485 3885);
FORCEPROP 0 LASTPIN (-5475 3825) $PN K1
J 2
(-5485 3835);
DISPLAY 0.489362 (-5485 3835);
PAINT MONO (-5485 3835);
FORCEPROP 0 LASTPIN (-5475 3775) $PN L6
J 2
(-5485 3785);
DISPLAY 0.489362 (-5485 3785);
PAINT MONO (-5485 3785);
FORCEPROP 0 LASTPIN (-5475 3725) $PN L5
J 2
(-5485 3735);
DISPLAY 0.489362 (-5485 3735);
PAINT MONO (-5485 3735);
FORCEPROP 0 LASTPIN (-5475 3675) $PN L1
J 2
(-5485 3685);
DISPLAY 0.489362 (-5485 3685);
PAINT MONO (-5485 3685);
FORCEPROP 0 LASTPIN (-5475 3625) $PN M2
J 2
(-5485 3635);
DISPLAY 0.489362 (-5485 3635);
PAINT MONO (-5485 3635);
FORCEPROP 0 LASTPIN (-5475 3575) $PN L3
J 2
(-5485 3585);
DISPLAY 0.489362 (-5485 3585);
PAINT MONO (-5485 3585);
FORCEPROP 0 LASTPIN (-5475 3525) $PN L4
J 2
(-5485 3535);
DISPLAY 0.489362 (-5485 3535);
PAINT MONO (-5485 3535);
FORCEPROP 0 LASTPIN (-4175 4075) $PN M1
J 0
(-4165 4085);
DISPLAY 0.489362 (-4165 4085);
PAINT MONO (-4165 4085);
FORCEPROP 0 LASTPIN (-4175 4025) $PN N1
J 0
(-4165 4035);
DISPLAY 0.489362 (-4165 4035);
PAINT MONO (-4165 4035);
FORCEPROP 0 LASTPIN (-4175 3975) $PN M6
J 0
(-4165 3985);
DISPLAY 0.489362 (-4165 3985);
PAINT MONO (-4165 3985);
FORCEPROP 0 LASTPIN (-4175 3925) $PN M5
J 0
(-4165 3935);
DISPLAY 0.489362 (-4165 3935);
PAINT MONO (-4165 3935);
FORCEPROP 0 LASTPIN (-4175 3875) $PN N2
J 0
(-4165 3885);
DISPLAY 0.489362 (-4165 3885);
PAINT MONO (-4165 3885);
FORCEPROP 0 LASTPIN (-4175 3825) $PN P1
J 0
(-4165 3835);
DISPLAY 0.489362 (-4165 3835);
PAINT MONO (-4165 3835);
FORCEPROP 0 LASTPIN (-4175 3775) $PN N3
J 0
(-4165 3785);
DISPLAY 0.489362 (-4165 3785);
PAINT MONO (-4165 3785);
FORCEPROP 0 LASTPIN (-4175 3725) $PN N4
J 0
(-4165 3735);
DISPLAY 0.489362 (-4165 3735);
PAINT MONO (-4165 3735);
FORCEPROP 0 LASTPIN (-4175 3675) $PN P2
J 0
(-4165 3685);
DISPLAY 0.489362 (-4165 3685);
PAINT MONO (-4165 3685);
FORCEPROP 0 LASTPIN (-4175 3625) $PN R1
J 0
(-4165 3635);
DISPLAY 0.489362 (-4165 3635);
PAINT MONO (-4165 3635);
FORCEPROP 0 LASTPIN (-4175 3575) $PN P3
J 0
(-4165 3585);
DISPLAY 0.489362 (-4165 3585);
PAINT MONO (-4165 3585);
FORCEPROP 0 LASTPIN (-4175 3525) $PN M7
J 0
(-4165 3535);
DISPLAY 0.489362 (-4165 3535);
PAINT MONO (-4165 3535);
FORCEPROP 0 LASTPIN (-5475 4175) $PN P4
J 2
(-5485 4185);
DISPLAY 0.489362 (-5485 4185);
PAINT MONO (-5485 4185);
FORCEPROP 0 LASTPIN (-5475 4225) $PN N5
J 2
(-5485 4235);
DISPLAY 0.489362 (-5485 4235);
PAINT MONO (-5485 4235);
FORCEPROP 0 LASTPIN (-5475 4275) $PN N6
J 2
(-5485 4285);
DISPLAY 0.489362 (-5485 4285);
PAINT MONO (-5485 4285);
FORCEPROP 0 LASTPIN (-5475 4325) $PN N7
J 2
(-5485 4335);
DISPLAY 0.489362 (-5485 4335);
PAINT MONO (-5485 4335);
FORCEPROP 0 LASTPIN (-5475 4375) $PN R2
J 2
(-5485 4385);
DISPLAY 0.489362 (-5485 4385);
PAINT MONO (-5485 4385);
FORCEPROP 0 LASTPIN (-5475 4425) $PN T1
J 2
(-5485 4435);
DISPLAY 0.489362 (-5485 4435);
PAINT MONO (-5485 4435);
FORCEPROP 0 LASTPIN (-5475 4475) $PN P5
J 2
(-5485 4485);
DISPLAY 0.489362 (-5485 4485);
PAINT MONO (-5485 4485);
FORCEPROP 0 LASTPIN (-5475 4525) $PN P6
J 2
(-5485 4535);
DISPLAY 0.489362 (-5485 4535);
PAINT MONO (-5485 4535);
FORCEPROP 0 LASTPIN (-5475 4575) $PN R3
J 2
(-5485 4585);
DISPLAY 0.489362 (-5485 4585);
PAINT MONO (-5485 4585);
FORCEPROP 0 LASTPIN (-5475 4625) $PN R4
J 2
(-5485 4635);
DISPLAY 0.489362 (-5485 4635);
PAINT MONO (-5485 4635);
FORCEPROP 0 LASTPIN (-5475 4675) $PN R5
J 2
(-5485 4685);
DISPLAY 0.489362 (-5485 4685);
PAINT MONO (-5485 4685);
FORCEPROP 0 LASTPIN (-5475 4725) $PN P7
J 2
(-5485 4735);
DISPLAY 0.489362 (-5485 4735);
PAINT MONO (-5485 4735);
FORCEPROP 0 LASTPIN (-5475 4775) $PN T2
J 2
(-5485 4785);
DISPLAY 0.489362 (-5485 4785);
PAINT MONO (-5485 4785);
FORCEPROP 0 LASTPIN (-5475 4825) $PN U1
J 2
(-5485 4835);
DISPLAY 0.489362 (-5485 4835);
PAINT MONO (-5485 4835);
FORCEPROP 0 LASTPIN (-5475 4875) $PN R6
J 2
(-5485 4885);
DISPLAY 0.489362 (-5485 4885);
PAINT MONO (-5485 4885);
FORCEPROP 0 LASTPIN (-5475 4925) $PN R7
J 2
(-5485 4935);
DISPLAY 0.489362 (-5485 4935);
PAINT MONO (-5485 4935);
FORCEPROP 0 LASTPIN (-5475 4975) $PN T3
J 2
(-5485 4985);
DISPLAY 0.489362 (-5485 4985);
PAINT MONO (-5485 4985);
FORCEPROP 0 LASTPIN (-5475 5025) $PN T4
J 2
(-5485 5035);
DISPLAY 0.489362 (-5485 5035);
PAINT MONO (-5485 5035);
FORCEPROP 0 LASTPIN (-5475 5075) $PN T5
J 2
(-5485 5085);
DISPLAY 0.489362 (-5485 5085);
PAINT MONO (-5485 5085);
FORCEPROP 0 LASTPIN (-5475 5125) $PN T6
J 2
(-5485 5135);
DISPLAY 0.489362 (-5485 5135);
PAINT MONO (-5485 5135);
FORCEPROP 0 LASTPIN (-4175 4375) $PN U2
J 0
(-4165 4385);
DISPLAY 0.489362 (-4165 4385);
PAINT MONO (-4165 4385);
FORCEPROP 0 LASTPIN (-4175 4425) $PN V1
J 0
(-4165 4435);
DISPLAY 0.489362 (-4165 4435);
PAINT MONO (-4165 4435);
FORCEPROP 0 LASTPIN (-4175 4475) $PN U3
J 0
(-4165 4485);
DISPLAY 0.489362 (-4165 4485);
PAINT MONO (-4165 4485);
FORCEPROP 0 LASTPIN (-4175 4525) $PN U4
J 0
(-4165 4535);
DISPLAY 0.489362 (-4165 4535);
PAINT MONO (-4165 4535);
FORCEPROP 0 LASTPIN (-4175 4575) $PN W1
J 0
(-4165 4585);
DISPLAY 0.489362 (-4165 4585);
PAINT MONO (-4165 4585);
FORCEPROP 0 LASTPIN (-4175 4625) $PN W2
J 0
(-4165 4635);
DISPLAY 0.489362 (-4165 4635);
PAINT MONO (-4165 4635);
FORCEPROP 0 LASTPIN (-4175 4675) $PN V4
J 0
(-4165 4685);
DISPLAY 0.489362 (-4165 4685);
PAINT MONO (-4165 4685);
FORCEPROP 0 LASTPIN (-4175 4725) $PN U5
J 0
(-4165 4735);
DISPLAY 0.489362 (-4165 4735);
PAINT MONO (-4165 4735);
FORCEPROP 0 LASTPIN (-4175 4775) $PN Y1
J 0
(-4165 4785);
DISPLAY 0.489362 (-4165 4785);
PAINT MONO (-4165 4785);
FORCEPROP 0 LASTPIN (-4175 4825) $PN AA1
J 0
(-4165 4835);
DISPLAY 0.489362 (-4165 4835);
PAINT MONO (-4165 4835);
FORCEPROP 0 LASTPIN (-4175 4875) $PN W3
J 0
(-4165 4885);
DISPLAY 0.489362 (-4165 4885);
PAINT MONO (-4165 4885);
FORCEPROP 0 LASTPIN (-4175 4925) $PN Y2
J 0
(-4165 4935);
DISPLAY 0.489362 (-4165 4935);
PAINT MONO (-4165 4935);
FORCEPROP 0 LASTPIN (-4175 4975) $PN Y3
J 0
(-4165 4985);
DISPLAY 0.489362 (-4165 4985);
PAINT MONO (-4165 4985);
FORCEPROP 0 LASTPIN (-4175 5025) $PN W4
J 0
(-4165 5035);
DISPLAY 0.489362 (-4165 5035);
PAINT MONO (-4165 5035);
FORCEPROP 0 LASTPIN (-4175 5075) $PN V5
J 0
(-4165 5085);
DISPLAY 0.489362 (-4165 5085);
PAINT MONO (-4165 5085);
FORCEPROP 0 LASTPIN (-4175 5125) $PN T7
J 0
(-4165 5135);
DISPLAY 0.489362 (-4165 5135);
PAINT MONO (-4165 5135);
FORCEPROP 2 LAST PART_TYPE SMLF
J 0
(-5320 6595);
DISPLAY 0.680851 (-5320 6595);
FORCEPROP 2 LAST VALUE LCMXO3D-9400HC-5BG484C
J 0
(-5320 6550);
DISPLAY 0.489362 (-5320 6550);
PAINT SKYBLUE (-5320 6550);
FORCEPROP 1 LAST PART_NUMBER AJ094000T05
J 0
(-5326 6365);
DISPLAY 0.489362 (-5326 6365);
PAINT SKYBLUE (-5326 6365);
FORCEPROP 1 LAST MATERIAL IC
J 0
(-5326 6238);
DISPLAY 0.489362 (-5326 6238);
PAINT SKYBLUE (-5326 6238);
FORCEPROP 1 LAST PATH I737
J 0
(-4825 4825);
DISPLAY 0.723404 (-4825 4825);
PAINT GREEN (-4825 4825);
DISPLAY INVISIBLE (-4825 4825);
FORCEPROP 1 LAST NEEDS_NO_SIZE TRUE
J 0
(-4825 4825);
DISPLAY 0.723404 (-4825 4825);
PAINT GREEN (-4825 4825);
DISPLAY INVISIBLE (-4825 4825);
FORCEPROP 1 LAST CDS_LMAN_SYM_OUTLINE -500,1400,500,-1400
J 0
(-4825 4825);
DISPLAY 0.468085 (-4825 4825);
PAINT GREEN (-4825 4825);
DISPLAY INVISIBLE (-4825 4825);
FORCEPROP 2 LAST CDS_LIB pure_quanta
J 0
(-4825 4825);
DISPLAY INVISIBLE (-4825 4825);
FORCEADD Q_RES..1
(-6425 6075);
FORCEPROP 1 LAST LOCATION R234
J 0
(-6300 6075);
DISPLAY 0.489362 (-6300 6075);
PAINT SKYBLUE (-6300 6075);
FORCEPROP 0 LAST $SEC 1
J 2
(-6300 6125);
DISPLAY 0.680851 (-6300 6125);
PAINT MONO (-6300 6125);
DISPLAY INVISIBLE (-6300 6125);
FORCEPROP 0 LAST CDS_SEC 1
J 2
(-6300 6125);
DISPLAY 1.021277 (-6300 6125);
DISPLAY INVISIBLE (-6300 6125);
FORCEPROP 1 LASTPIN (-6525 6075) $PN 1
J 0
(-6513 6087);
DISPLAY 0.489362 (-6513 6087);
PAINT MONO (-6513 6087);
FORCEPROP 1 LASTPIN (-6325 6075) $PN 2
J 0
(-6363 6087);
DISPLAY 0.489362 (-6363 6087);
PAINT MONO (-6363 6087);
FORCEPROP 1 LAST VALUE 0
J 2
(-6550 6075);
DISPLAY 0.489362 (-6550 6075);
PAINT SKYBLUE (-6550 6075);
FORCEPROP 2 LAST ROOM RST_CPU0_PLD_TO_DIMM
J 2
(-6400 6175);
DISPLAY 0.744681 (-6400 6175);
PAINT RED (-6400 6175);
DISPLAY INVISIBLE (-6400 6175);
FORCEPROP 1 LAST PACK_TYPE 0402LF
J 2
(-6250 6000);
DISPLAY 0.489362 (-6250 6000);
PAINT SKYBLUE (-6250 6000);
DISPLAY INVISIBLE (-6250 6000);
FORCEPROP 1 LAST PART_NUMBER CS00002JB38
J 2
(-6325 6125);
DISPLAY 0.489362 (-6325 6125);
PAINT SKYBLUE (-6325 6125);
DISPLAY INVISIBLE (-6325 6125);
FORCEPROP 1 LAST TOLERANCE 5%
J 0
(-6550 6050);
DISPLAY 0.489362 (-6550 6050);
PAINT SKYBLUE (-6550 6050);
DISPLAY INVISIBLE (-6550 6050);
FORCEPROP 1 LAST MATERIAL CHIP
J 2
(-6250 6050);
DISPLAY 0.489362 (-6250 6050);
PAINT SKYBLUE (-6250 6050);
DISPLAY INVISIBLE (-6250 6050);
FORCEPROP 1 LAST WATTAGE 1/16W
J 2
(-6500 6000);
DISPLAY 0.489362 (-6500 6000);
PAINT SKYBLUE (-6500 6000);
DISPLAY INVISIBLE (-6500 6000);
FORCEPROP 1 LAST PATH I738
J 0
(-6475 6225);
DISPLAY 0.978723 (-6475 6225);
PAINT WHITE (-6475 6225);
DISPLAY INVISIBLE (-6475 6225);
FORCEPROP 2 LAST BOM_COST MEM
J 2
(-6400 6225);
DISPLAY 0.744681 (-6400 6225);
PAINT WHITE (-6400 6225);
DISPLAY INVISIBLE (-6400 6225);
FORCEPROP 2 LAST CDS_LIB pure_quanta
J 2
(-6425 6075);
DISPLAY INVISIBLE (-6425 6075);
FORCEADD Q_RES..1
(-6425 6125);
FORCEPROP 1 LAST LOCATION R205
J 0
(-6300 6125);
DISPLAY 0.489362 (-6300 6125);
PAINT SKYBLUE (-6300 6125);
FORCEPROP 0 LAST $SEC 1
J 2
(-6300 6175);
DISPLAY 0.680851 (-6300 6175);
PAINT MONO (-6300 6175);
DISPLAY INVISIBLE (-6300 6175);
FORCEPROP 0 LAST CDS_SEC 1
J 2
(-6300 6175);
DISPLAY 1.021277 (-6300 6175);
DISPLAY INVISIBLE (-6300 6175);
FORCEPROP 1 LASTPIN (-6525 6125) $PN 1
J 0
(-6513 6137);
DISPLAY 0.489362 (-6513 6137);
PAINT MONO (-6513 6137);
FORCEPROP 1 LASTPIN (-6325 6125) $PN 2
J 0
(-6363 6137);
DISPLAY 0.489362 (-6363 6137);
PAINT MONO (-6363 6137);
FORCEPROP 1 LAST VALUE 0
J 2
(-6550 6125);
DISPLAY 0.489362 (-6550 6125);
PAINT SKYBLUE (-6550 6125);
FORCEPROP 2 LAST ROOM RST_CPU0_PLD_TO_DIMM
J 2
(-6400 6225);
DISPLAY 0.744681 (-6400 6225);
PAINT RED (-6400 6225);
DISPLAY INVISIBLE (-6400 6225);
FORCEPROP 1 LAST PACK_TYPE 0402LF
J 2
(-6250 6050);
DISPLAY 0.489362 (-6250 6050);
PAINT SKYBLUE (-6250 6050);
DISPLAY INVISIBLE (-6250 6050);
FORCEPROP 1 LAST PART_NUMBER CS00002JB38
J 2
(-6325 6175);
DISPLAY 0.489362 (-6325 6175);
PAINT SKYBLUE (-6325 6175);
DISPLAY INVISIBLE (-6325 6175);
FORCEPROP 1 LAST TOLERANCE 5%
J 0
(-6550 6100);
DISPLAY 0.489362 (-6550 6100);
PAINT SKYBLUE (-6550 6100);
DISPLAY INVISIBLE (-6550 6100);
FORCEPROP 1 LAST MATERIAL CHIP
J 2
(-6250 6100);
DISPLAY 0.489362 (-6250 6100);
PAINT SKYBLUE (-6250 6100);
DISPLAY INVISIBLE (-6250 6100);
FORCEPROP 1 LAST WATTAGE 1/16W
J 2
(-6500 6050);
DISPLAY 0.489362 (-6500 6050);
PAINT SKYBLUE (-6500 6050);
DISPLAY INVISIBLE (-6500 6050);
FORCEPROP 1 LAST PATH I739
J 0
(-6475 6275);
DISPLAY 0.978723 (-6475 6275);
PAINT WHITE (-6475 6275);
DISPLAY INVISIBLE (-6475 6275);
FORCEPROP 2 LAST BOM_COST MEM
J 2
(-6400 6275);
DISPLAY 0.744681 (-6400 6275);
PAINT WHITE (-6400 6275);
DISPLAY INVISIBLE (-6400 6275);
FORCEPROP 2 LAST CDS_LIB pure_quanta
J 2
(-6425 6125);
DISPLAY INVISIBLE (-6425 6125);
FORCEADD Q_RES..1
(-6425 6175);
FORCEPROP 1 LAST LOCATION R204
J 0
(-6300 6175);
DISPLAY 0.489362 (-6300 6175);
PAINT SKYBLUE (-6300 6175);
FORCEPROP 0 LAST $SEC 1
J 2
(-6300 6225);
DISPLAY 0.680851 (-6300 6225);
PAINT MONO (-6300 6225);
DISPLAY INVISIBLE (-6300 6225);
FORCEPROP 0 LAST CDS_SEC 1
J 2
(-6300 6225);
DISPLAY 1.021277 (-6300 6225);
DISPLAY INVISIBLE (-6300 6225);
FORCEPROP 1 LASTPIN (-6525 6175) $PN 1
J 0
(-6513 6187);
DISPLAY 0.489362 (-6513 6187);
PAINT MONO (-6513 6187);
FORCEPROP 1 LASTPIN (-6325 6175) $PN 2
J 0
(-6363 6187);
DISPLAY 0.489362 (-6363 6187);
PAINT MONO (-6363 6187);
FORCEPROP 1 LAST VALUE 0
J 2
(-6550 6175);
DISPLAY 0.489362 (-6550 6175);
PAINT SKYBLUE (-6550 6175);
FORCEPROP 2 LAST ROOM RST_CPU0_PLD_TO_DIMM
J 2
(-6400 6275);
DISPLAY 0.744681 (-6400 6275);
PAINT RED (-6400 6275);
DISPLAY INVISIBLE (-6400 6275);
FORCEPROP 1 LAST PACK_TYPE 0402LF
J 2
(-6250 6100);
DISPLAY 0.489362 (-6250 6100);
PAINT SKYBLUE (-6250 6100);
DISPLAY INVISIBLE (-6250 6100);
FORCEPROP 1 LAST PART_NUMBER CS00002JB38
J 2
(-6325 6225);
DISPLAY 0.489362 (-6325 6225);
PAINT SKYBLUE (-6325 6225);
DISPLAY INVISIBLE (-6325 6225);
FORCEPROP 1 LAST TOLERANCE 5%
J 0
(-6550 6150);
DISPLAY 0.489362 (-6550 6150);
PAINT SKYBLUE (-6550 6150);
DISPLAY INVISIBLE (-6550 6150);
FORCEPROP 1 LAST MATERIAL CHIP
J 2
(-6250 6150);
DISPLAY 0.489362 (-6250 6150);
PAINT SKYBLUE (-6250 6150);
DISPLAY INVISIBLE (-6250 6150);
FORCEPROP 1 LAST WATTAGE 1/16W
J 2
(-6500 6100);
DISPLAY 0.489362 (-6500 6100);
PAINT SKYBLUE (-6500 6100);
DISPLAY INVISIBLE (-6500 6100);
FORCEPROP 1 LAST PATH I740
J 0
(-6475 6325);
DISPLAY 0.978723 (-6475 6325);
PAINT WHITE (-6475 6325);
DISPLAY INVISIBLE (-6475 6325);
FORCEPROP 2 LAST BOM_COST MEM
J 2
(-6400 6325);
DISPLAY 0.744681 (-6400 6325);
PAINT WHITE (-6400 6325);
DISPLAY INVISIBLE (-6400 6325);
FORCEPROP 2 LAST CDS_LIB pure_quanta
J 2
(-6425 6175);
DISPLAY INVISIBLE (-6425 6175);
FORCEADD Q_RES..1
(-6425 5975);
FORCEPROP 1 LAST LOCATION R238
J 0
(-6300 5975);
DISPLAY 0.489362 (-6300 5975);
PAINT SKYBLUE (-6300 5975);
FORCEPROP 0 LAST $SEC 1
J 2
(-6300 6025);
DISPLAY 0.680851 (-6300 6025);
PAINT MONO (-6300 6025);
DISPLAY INVISIBLE (-6300 6025);
FORCEPROP 0 LAST CDS_SEC 1
J 2
(-6300 6025);
DISPLAY 1.021277 (-6300 6025);
DISPLAY INVISIBLE (-6300 6025);
FORCEPROP 1 LASTPIN (-6525 5975) $PN 1
J 0
(-6513 5987);
DISPLAY 0.489362 (-6513 5987);
PAINT MONO (-6513 5987);
FORCEPROP 1 LASTPIN (-6325 5975) $PN 2
J 0
(-6363 5987);
DISPLAY 0.489362 (-6363 5987);
PAINT MONO (-6363 5987);
FORCEPROP 1 LAST VALUE 0
J 2
(-6550 5975);
DISPLAY 0.489362 (-6550 5975);
PAINT SKYBLUE (-6550 5975);
FORCEPROP 2 LAST ROOM RST_CPU0_PLD_TO_DIMM
J 2
(-6400 6075);
DISPLAY 0.744681 (-6400 6075);
PAINT RED (-6400 6075);
DISPLAY INVISIBLE (-6400 6075);
FORCEPROP 1 LAST PACK_TYPE 0402LF
J 2
(-6250 5900);
DISPLAY 0.489362 (-6250 5900);
PAINT SKYBLUE (-6250 5900);
DISPLAY INVISIBLE (-6250 5900);
FORCEPROP 1 LAST PART_NUMBER CS00002JB38
J 2
(-6325 6025);
DISPLAY 0.489362 (-6325 6025);
PAINT SKYBLUE (-6325 6025);
DISPLAY INVISIBLE (-6325 6025);
FORCEPROP 1 LAST TOLERANCE 5%
J 0
(-6550 5950);
DISPLAY 0.489362 (-6550 5950);
PAINT SKYBLUE (-6550 5950);
DISPLAY INVISIBLE (-6550 5950);
FORCEPROP 1 LAST MATERIAL CHIP
J 2
(-6250 5950);
DISPLAY 0.489362 (-6250 5950);
PAINT SKYBLUE (-6250 5950);
DISPLAY INVISIBLE (-6250 5950);
FORCEPROP 1 LAST WATTAGE 1/16W
J 2
(-6500 5900);
DISPLAY 0.489362 (-6500 5900);
PAINT SKYBLUE (-6500 5900);
DISPLAY INVISIBLE (-6500 5900);
FORCEPROP 1 LAST PATH I741
J 0
(-6475 6125);
DISPLAY 0.978723 (-6475 6125);
PAINT WHITE (-6475 6125);
DISPLAY INVISIBLE (-6475 6125);
FORCEPROP 2 LAST CDS_LIB pure_quanta
J 2
(-6425 5975);
DISPLAY INVISIBLE (-6425 5975);
FORCEPROP 2 LAST BOM_COST MEM
J 2
(-6400 6125);
DISPLAY 0.744681 (-6400 6125);
PAINT WHITE (-6400 6125);
DISPLAY INVISIBLE (-6400 6125);
FORCEADD Q_RES..1
(-6425 5925);
FORCEPROP 1 LAST LOCATION R244
J 0
(-6300 5925);
DISPLAY 0.489362 (-6300 5925);
PAINT SKYBLUE (-6300 5925);
FORCEPROP 0 LAST $SEC 1
J 2
(-6300 5975);
DISPLAY 0.680851 (-6300 5975);
PAINT MONO (-6300 5975);
DISPLAY INVISIBLE (-6300 5975);
FORCEPROP 0 LAST CDS_SEC 1
J 2
(-6300 5975);
DISPLAY 1.021277 (-6300 5975);
DISPLAY INVISIBLE (-6300 5975);
FORCEPROP 1 LASTPIN (-6525 5925) $PN 1
J 0
(-6513 5937);
DISPLAY 0.489362 (-6513 5937);
PAINT MONO (-6513 5937);
FORCEPROP 1 LASTPIN (-6325 5925) $PN 2
J 0
(-6363 5937);
DISPLAY 0.489362 (-6363 5937);
PAINT MONO (-6363 5937);
FORCEPROP 1 LAST VALUE 0
J 2
(-6550 5925);
DISPLAY 0.489362 (-6550 5925);
PAINT SKYBLUE (-6550 5925);
FORCEPROP 2 LAST ROOM RST_CPU0_PLD_TO_DIMM
J 2
(-6400 6025);
DISPLAY 0.744681 (-6400 6025);
PAINT RED (-6400 6025);
DISPLAY INVISIBLE (-6400 6025);
FORCEPROP 1 LAST PACK_TYPE 0402LF
J 2
(-6250 5850);
DISPLAY 0.489362 (-6250 5850);
PAINT SKYBLUE (-6250 5850);
DISPLAY INVISIBLE (-6250 5850);
FORCEPROP 1 LAST PART_NUMBER CS00002JB38
J 2
(-6325 5975);
DISPLAY 0.489362 (-6325 5975);
PAINT SKYBLUE (-6325 5975);
DISPLAY INVISIBLE (-6325 5975);
FORCEPROP 1 LAST TOLERANCE 5%
J 0
(-6550 5900);
DISPLAY 0.489362 (-6550 5900);
PAINT SKYBLUE (-6550 5900);
DISPLAY INVISIBLE (-6550 5900);
FORCEPROP 1 LAST MATERIAL CHIP
J 2
(-6250 5900);
DISPLAY 0.489362 (-6250 5900);
PAINT SKYBLUE (-6250 5900);
DISPLAY INVISIBLE (-6250 5900);
FORCEPROP 1 LAST WATTAGE 1/16W
J 2
(-6500 5850);
DISPLAY 0.489362 (-6500 5850);
PAINT SKYBLUE (-6500 5850);
DISPLAY INVISIBLE (-6500 5850);
FORCEPROP 1 LAST PATH I742
J 0
(-6475 6075);
DISPLAY 0.978723 (-6475 6075);
PAINT WHITE (-6475 6075);
DISPLAY INVISIBLE (-6475 6075);
FORCEPROP 2 LAST BOM_COST MEM
J 2
(-6400 6075);
DISPLAY 0.744681 (-6400 6075);
PAINT WHITE (-6400 6075);
DISPLAY INVISIBLE (-6400 6075);
FORCEPROP 2 LAST CDS_LIB pure_quanta
J 2
(-6425 5925);
DISPLAY INVISIBLE (-6425 5925);
FORCEADD Q_RES..1
(-6425 5875);
FORCEPROP 1 LAST LOCATION R235
J 0
(-6300 5875);
DISPLAY 0.489362 (-6300 5875);
PAINT SKYBLUE (-6300 5875);
FORCEPROP 0 LAST $SEC 1
J 2
(-6300 5925);
DISPLAY 0.680851 (-6300 5925);
PAINT MONO (-6300 5925);
DISPLAY INVISIBLE (-6300 5925);
FORCEPROP 0 LAST CDS_SEC 1
J 2
(-6300 5925);
DISPLAY 1.021277 (-6300 5925);
DISPLAY INVISIBLE (-6300 5925);
FORCEPROP 1 LASTPIN (-6525 5875) $PN 1
J 0
(-6513 5887);
DISPLAY 0.489362 (-6513 5887);
PAINT MONO (-6513 5887);
FORCEPROP 1 LASTPIN (-6325 5875) $PN 2
J 0
(-6363 5887);
DISPLAY 0.489362 (-6363 5887);
PAINT MONO (-6363 5887);
FORCEPROP 1 LAST VALUE 0
J 2
(-6550 5875);
DISPLAY 0.489362 (-6550 5875);
PAINT SKYBLUE (-6550 5875);
FORCEPROP 2 LAST ROOM RST_CPU0_PLD_TO_DIMM
J 2
(-6400 5975);
DISPLAY 0.744681 (-6400 5975);
PAINT RED (-6400 5975);
DISPLAY INVISIBLE (-6400 5975);
FORCEPROP 1 LAST PACK_TYPE 0402LF
J 2
(-6250 5800);
DISPLAY 0.489362 (-6250 5800);
PAINT SKYBLUE (-6250 5800);
DISPLAY INVISIBLE (-6250 5800);
FORCEPROP 1 LAST PART_NUMBER CS00002JB38
J 2
(-6325 5925);
DISPLAY 0.489362 (-6325 5925);
PAINT SKYBLUE (-6325 5925);
DISPLAY INVISIBLE (-6325 5925);
FORCEPROP 1 LAST TOLERANCE 5%
J 0
(-6550 5850);
DISPLAY 0.489362 (-6550 5850);
PAINT SKYBLUE (-6550 5850);
DISPLAY INVISIBLE (-6550 5850);
FORCEPROP 1 LAST MATERIAL CHIP
J 2
(-6250 5850);
DISPLAY 0.489362 (-6250 5850);
PAINT SKYBLUE (-6250 5850);
DISPLAY INVISIBLE (-6250 5850);
FORCEPROP 1 LAST WATTAGE 1/16W
J 2
(-6500 5800);
DISPLAY 0.489362 (-6500 5800);
PAINT SKYBLUE (-6500 5800);
DISPLAY INVISIBLE (-6500 5800);
FORCEPROP 1 LAST PATH I743
J 0
(-6475 6025);
DISPLAY 0.978723 (-6475 6025);
PAINT WHITE (-6475 6025);
DISPLAY INVISIBLE (-6475 6025);
FORCEPROP 2 LAST BOM_COST MEM
J 2
(-6400 6025);
DISPLAY 0.744681 (-6400 6025);
PAINT WHITE (-6400 6025);
DISPLAY INVISIBLE (-6400 6025);
FORCEPROP 2 LAST CDS_LIB pure_quanta
J 2
(-6425 5875);
DISPLAY INVISIBLE (-6425 5875);
FORCEADD Q_RES..1
(-6425 5825);
FORCEPROP 1 LAST LOCATION R187
J 0
(-6300 5825);
DISPLAY 0.489362 (-6300 5825);
PAINT SKYBLUE (-6300 5825);
FORCEPROP 0 LAST $SEC 1
J 2
(-6300 5875);
DISPLAY 0.680851 (-6300 5875);
PAINT MONO (-6300 5875);
DISPLAY INVISIBLE (-6300 5875);
FORCEPROP 0 LAST CDS_SEC 1
J 2
(-6300 5875);
DISPLAY 1.021277 (-6300 5875);
DISPLAY INVISIBLE (-6300 5875);
FORCEPROP 1 LASTPIN (-6525 5825) $PN 1
J 0
(-6513 5837);
DISPLAY 0.489362 (-6513 5837);
PAINT MONO (-6513 5837);
FORCEPROP 1 LASTPIN (-6325 5825) $PN 2
J 0
(-6363 5837);
DISPLAY 0.489362 (-6363 5837);
PAINT MONO (-6363 5837);
FORCEPROP 1 LAST VALUE 0
J 2
(-6550 5825);
DISPLAY 0.489362 (-6550 5825);
PAINT SKYBLUE (-6550 5825);
FORCEPROP 2 LAST ROOM RST_CPU0_PLD_TO_DIMM
J 2
(-6400 5925);
DISPLAY 0.744681 (-6400 5925);
PAINT RED (-6400 5925);
DISPLAY INVISIBLE (-6400 5925);
FORCEPROP 1 LAST PACK_TYPE 0402LF
J 2
(-6250 5750);
DISPLAY 0.489362 (-6250 5750);
PAINT SKYBLUE (-6250 5750);
DISPLAY INVISIBLE (-6250 5750);
FORCEPROP 1 LAST PART_NUMBER CS00002JB38
J 2
(-6325 5875);
DISPLAY 0.489362 (-6325 5875);
PAINT SKYBLUE (-6325 5875);
DISPLAY INVISIBLE (-6325 5875);
FORCEPROP 1 LAST TOLERANCE 5%
J 0
(-6550 5800);
DISPLAY 0.489362 (-6550 5800);
PAINT SKYBLUE (-6550 5800);
DISPLAY INVISIBLE (-6550 5800);
FORCEPROP 1 LAST MATERIAL CHIP
J 2
(-6250 5800);
DISPLAY 0.489362 (-6250 5800);
PAINT SKYBLUE (-6250 5800);
DISPLAY INVISIBLE (-6250 5800);
FORCEPROP 1 LAST WATTAGE 1/16W
J 2
(-6500 5750);
DISPLAY 0.489362 (-6500 5750);
PAINT SKYBLUE (-6500 5750);
DISPLAY INVISIBLE (-6500 5750);
FORCEPROP 1 LAST PATH I744
J 0
(-6475 5975);
DISPLAY 0.978723 (-6475 5975);
PAINT WHITE (-6475 5975);
DISPLAY INVISIBLE (-6475 5975);
FORCEPROP 2 LAST CDS_LIB pure_quanta
J 2
(-6425 5825);
DISPLAY INVISIBLE (-6425 5825);
FORCEPROP 2 LAST BOM_COST MEM
J 2
(-6400 5975);
DISPLAY 0.744681 (-6400 5975);
PAINT WHITE (-6400 5975);
DISPLAY INVISIBLE (-6400 5975);
FORCEADD Q_RES..1
(-6425 5725);
FORCEPROP 1 LAST LOCATION R236
J 0
(-6300 5725);
DISPLAY 0.489362 (-6300 5725);
PAINT SKYBLUE (-6300 5725);
FORCEPROP 0 LAST $SEC 1
J 2
(-6300 5775);
DISPLAY 0.680851 (-6300 5775);
PAINT MONO (-6300 5775);
DISPLAY INVISIBLE (-6300 5775);
FORCEPROP 0 LAST CDS_SEC 1
J 2
(-6300 5775);
DISPLAY 1.021277 (-6300 5775);
DISPLAY INVISIBLE (-6300 5775);
FORCEPROP 1 LASTPIN (-6525 5725) $PN 1
J 0
(-6513 5737);
DISPLAY 0.489362 (-6513 5737);
PAINT MONO (-6513 5737);
FORCEPROP 1 LASTPIN (-6325 5725) $PN 2
J 0
(-6363 5737);
DISPLAY 0.489362 (-6363 5737);
PAINT MONO (-6363 5737);
FORCEPROP 1 LAST VALUE 0
J 2
(-6550 5725);
DISPLAY 0.489362 (-6550 5725);
PAINT SKYBLUE (-6550 5725);
FORCEPROP 2 LAST ROOM RST_CPU0_PLD_TO_DIMM
J 2
(-6400 5825);
DISPLAY 0.744681 (-6400 5825);
PAINT RED (-6400 5825);
DISPLAY INVISIBLE (-6400 5825);
FORCEPROP 1 LAST PACK_TYPE 0402LF
J 2
(-6250 5650);
DISPLAY 0.489362 (-6250 5650);
PAINT SKYBLUE (-6250 5650);
DISPLAY INVISIBLE (-6250 5650);
FORCEPROP 1 LAST PART_NUMBER CS00002JB38
J 2
(-6325 5775);
DISPLAY 0.489362 (-6325 5775);
PAINT SKYBLUE (-6325 5775);
DISPLAY INVISIBLE (-6325 5775);
FORCEPROP 1 LAST TOLERANCE 5%
J 0
(-6550 5700);
DISPLAY 0.489362 (-6550 5700);
PAINT SKYBLUE (-6550 5700);
DISPLAY INVISIBLE (-6550 5700);
FORCEPROP 1 LAST MATERIAL CHIP
J 2
(-6250 5700);
DISPLAY 0.489362 (-6250 5700);
PAINT SKYBLUE (-6250 5700);
DISPLAY INVISIBLE (-6250 5700);
FORCEPROP 1 LAST WATTAGE 1/16W
J 2
(-6500 5650);
DISPLAY 0.489362 (-6500 5650);
PAINT SKYBLUE (-6500 5650);
DISPLAY INVISIBLE (-6500 5650);
FORCEPROP 1 LAST PATH I745
J 0
(-6475 5875);
DISPLAY 0.978723 (-6475 5875);
PAINT WHITE (-6475 5875);
DISPLAY INVISIBLE (-6475 5875);
FORCEPROP 2 LAST CDS_LIB pure_quanta
J 2
(-6425 5725);
DISPLAY INVISIBLE (-6425 5725);
FORCEPROP 2 LAST BOM_COST MEM
J 2
(-6400 5875);
DISPLAY 0.744681 (-6400 5875);
PAINT WHITE (-6400 5875);
DISPLAY INVISIBLE (-6400 5875);
FORCEADD Q_RES..1
(-6425 5775);
FORCEPROP 1 LAST LOCATION R237
J 0
(-6300 5775);
DISPLAY 0.489362 (-6300 5775);
PAINT SKYBLUE (-6300 5775);
FORCEPROP 0 LAST $SEC 1
J 2
(-6300 5825);
DISPLAY 0.680851 (-6300 5825);
PAINT MONO (-6300 5825);
DISPLAY INVISIBLE (-6300 5825);
FORCEPROP 0 LAST CDS_SEC 1
J 2
(-6300 5825);
DISPLAY 1.021277 (-6300 5825);
DISPLAY INVISIBLE (-6300 5825);
FORCEPROP 1 LASTPIN (-6525 5775) $PN 1
J 0
(-6513 5787);
DISPLAY 0.489362 (-6513 5787);
PAINT MONO (-6513 5787);
FORCEPROP 1 LASTPIN (-6325 5775) $PN 2
J 0
(-6363 5787);
DISPLAY 0.489362 (-6363 5787);
PAINT MONO (-6363 5787);
FORCEPROP 1 LAST VALUE 0
J 2
(-6550 5775);
DISPLAY 0.489362 (-6550 5775);
PAINT SKYBLUE (-6550 5775);
FORCEPROP 2 LAST ROOM RST_CPU0_PLD_TO_DIMM
J 2
(-6400 5875);
DISPLAY 0.744681 (-6400 5875);
PAINT RED (-6400 5875);
DISPLAY INVISIBLE (-6400 5875);
FORCEPROP 1 LAST PACK_TYPE 0402LF
J 2
(-6250 5700);
DISPLAY 0.489362 (-6250 5700);
PAINT SKYBLUE (-6250 5700);
DISPLAY INVISIBLE (-6250 5700);
FORCEPROP 1 LAST PART_NUMBER CS00002JB38
J 2
(-6325 5825);
DISPLAY 0.489362 (-6325 5825);
PAINT SKYBLUE (-6325 5825);
DISPLAY INVISIBLE (-6325 5825);
FORCEPROP 1 LAST TOLERANCE 5%
J 0
(-6550 5750);
DISPLAY 0.489362 (-6550 5750);
PAINT SKYBLUE (-6550 5750);
DISPLAY INVISIBLE (-6550 5750);
FORCEPROP 1 LAST MATERIAL CHIP
J 2
(-6250 5750);
DISPLAY 0.489362 (-6250 5750);
PAINT SKYBLUE (-6250 5750);
DISPLAY INVISIBLE (-6250 5750);
FORCEPROP 1 LAST WATTAGE 1/16W
J 2
(-6500 5700);
DISPLAY 0.489362 (-6500 5700);
PAINT SKYBLUE (-6500 5700);
DISPLAY INVISIBLE (-6500 5700);
FORCEPROP 1 LAST PATH I746
J 0
(-6475 5925);
DISPLAY 0.978723 (-6475 5925);
PAINT WHITE (-6475 5925);
DISPLAY INVISIBLE (-6475 5925);
FORCEPROP 2 LAST CDS_LIB pure_quanta
J 2
(-6425 5775);
DISPLAY INVISIBLE (-6425 5775);
FORCEPROP 2 LAST BOM_COST MEM
J 2
(-6400 5925);
DISPLAY 0.744681 (-6400 5925);
PAINT WHITE (-6400 5925);
DISPLAY INVISIBLE (-6400 5925);
FORCEADD Q_RES..1
(-6425 5675);
FORCEPROP 1 LAST LOCATION R245
J 0
(-6300 5675);
DISPLAY 0.489362 (-6300 5675);
PAINT SKYBLUE (-6300 5675);
FORCEPROP 0 LAST $SEC 1
J 2
(-6300 5725);
DISPLAY 0.680851 (-6300 5725);
PAINT MONO (-6300 5725);
DISPLAY INVISIBLE (-6300 5725);
FORCEPROP 0 LAST CDS_SEC 1
J 2
(-6300 5725);
DISPLAY 1.021277 (-6300 5725);
DISPLAY INVISIBLE (-6300 5725);
FORCEPROP 1 LASTPIN (-6525 5675) $PN 1
J 0
(-6513 5687);
DISPLAY 0.489362 (-6513 5687);
PAINT MONO (-6513 5687);
FORCEPROP 1 LASTPIN (-6325 5675) $PN 2
J 0
(-6363 5687);
DISPLAY 0.489362 (-6363 5687);
PAINT MONO (-6363 5687);
FORCEPROP 1 LAST VALUE 0
J 2
(-6550 5675);
DISPLAY 0.489362 (-6550 5675);
PAINT SKYBLUE (-6550 5675);
FORCEPROP 2 LAST ROOM RST_CPU0_PLD_TO_DIMM
J 2
(-6400 5775);
DISPLAY 0.744681 (-6400 5775);
PAINT RED (-6400 5775);
DISPLAY INVISIBLE (-6400 5775);
FORCEPROP 1 LAST PACK_TYPE 0402LF
J 2
(-6250 5600);
DISPLAY 0.489362 (-6250 5600);
PAINT SKYBLUE (-6250 5600);
DISPLAY INVISIBLE (-6250 5600);
FORCEPROP 1 LAST PART_NUMBER CS00002JB38
J 2
(-6325 5725);
DISPLAY 0.489362 (-6325 5725);
PAINT SKYBLUE (-6325 5725);
DISPLAY INVISIBLE (-6325 5725);
FORCEPROP 1 LAST TOLERANCE 5%
J 0
(-6550 5650);
DISPLAY 0.489362 (-6550 5650);
PAINT SKYBLUE (-6550 5650);
DISPLAY INVISIBLE (-6550 5650);
FORCEPROP 1 LAST MATERIAL CHIP
J 2
(-6250 5650);
DISPLAY 0.489362 (-6250 5650);
PAINT SKYBLUE (-6250 5650);
DISPLAY INVISIBLE (-6250 5650);
FORCEPROP 1 LAST WATTAGE 1/16W
J 2
(-6500 5600);
DISPLAY 0.489362 (-6500 5600);
PAINT SKYBLUE (-6500 5600);
DISPLAY INVISIBLE (-6500 5600);
FORCEPROP 1 LAST PATH I747
J 0
(-6475 5825);
DISPLAY 0.978723 (-6475 5825);
PAINT WHITE (-6475 5825);
DISPLAY INVISIBLE (-6475 5825);
FORCEPROP 2 LAST BOM_COST MEM
J 2
(-6400 5825);
DISPLAY 0.744681 (-6400 5825);
PAINT WHITE (-6400 5825);
DISPLAY INVISIBLE (-6400 5825);
FORCEPROP 2 LAST CDS_LIB pure_quanta
J 2
(-6425 5675);
DISPLAY INVISIBLE (-6425 5675);
FORCEADD Q_RES..1
(-6425 5625);
FORCEPROP 1 LAST LOCATION R246
J 0
(-6300 5625);
DISPLAY 0.489362 (-6300 5625);
PAINT SKYBLUE (-6300 5625);
FORCEPROP 0 LAST $SEC 1
J 2
(-6300 5675);
DISPLAY 0.680851 (-6300 5675);
PAINT MONO (-6300 5675);
DISPLAY INVISIBLE (-6300 5675);
FORCEPROP 0 LAST CDS_SEC 1
J 2
(-6300 5675);
DISPLAY 1.021277 (-6300 5675);
DISPLAY INVISIBLE (-6300 5675);
FORCEPROP 1 LASTPIN (-6525 5625) $PN 1
J 0
(-6513 5637);
DISPLAY 0.489362 (-6513 5637);
PAINT MONO (-6513 5637);
FORCEPROP 1 LASTPIN (-6325 5625) $PN 2
J 0
(-6363 5637);
DISPLAY 0.489362 (-6363 5637);
PAINT MONO (-6363 5637);
FORCEPROP 1 LAST VALUE 0
J 2
(-6550 5625);
DISPLAY 0.489362 (-6550 5625);
PAINT SKYBLUE (-6550 5625);
FORCEPROP 2 LAST ROOM RST_CPU0_PLD_TO_DIMM
J 2
(-6400 5725);
DISPLAY 0.744681 (-6400 5725);
PAINT RED (-6400 5725);
DISPLAY INVISIBLE (-6400 5725);
FORCEPROP 1 LAST PACK_TYPE 0402LF
J 2
(-6250 5550);
DISPLAY 0.489362 (-6250 5550);
PAINT SKYBLUE (-6250 5550);
DISPLAY INVISIBLE (-6250 5550);
FORCEPROP 1 LAST PART_NUMBER CS00002JB38
J 2
(-6325 5675);
DISPLAY 0.489362 (-6325 5675);
PAINT SKYBLUE (-6325 5675);
DISPLAY INVISIBLE (-6325 5675);
FORCEPROP 1 LAST TOLERANCE 5%
J 0
(-6550 5600);
DISPLAY 0.489362 (-6550 5600);
PAINT SKYBLUE (-6550 5600);
DISPLAY INVISIBLE (-6550 5600);
FORCEPROP 1 LAST MATERIAL CHIP
J 2
(-6250 5600);
DISPLAY 0.489362 (-6250 5600);
PAINT SKYBLUE (-6250 5600);
DISPLAY INVISIBLE (-6250 5600);
FORCEPROP 1 LAST WATTAGE 1/16W
J 2
(-6500 5550);
DISPLAY 0.489362 (-6500 5550);
PAINT SKYBLUE (-6500 5550);
DISPLAY INVISIBLE (-6500 5550);
FORCEPROP 1 LAST PATH I748
J 0
(-6475 5775);
DISPLAY 0.978723 (-6475 5775);
PAINT WHITE (-6475 5775);
DISPLAY INVISIBLE (-6475 5775);
FORCEPROP 2 LAST CDS_LIB pure_quanta
J 2
(-6425 5625);
DISPLAY INVISIBLE (-6425 5625);
FORCEPROP 2 LAST BOM_COST MEM
J 2
(-6400 5775);
DISPLAY 0.744681 (-6400 5775);
PAINT WHITE (-6400 5775);
DISPLAY INVISIBLE (-6400 5775);
FORCEADD Q_RES..1
(-6425 5575);
FORCEPROP 1 LAST LOCATION R243
J 0
(-6300 5575);
DISPLAY 0.489362 (-6300 5575);
PAINT SKYBLUE (-6300 5575);
FORCEPROP 0 LAST $SEC 1
J 2
(-6300 5625);
DISPLAY 0.680851 (-6300 5625);
PAINT MONO (-6300 5625);
DISPLAY INVISIBLE (-6300 5625);
FORCEPROP 0 LAST CDS_SEC 1
J 2
(-6300 5625);
DISPLAY 1.021277 (-6300 5625);
DISPLAY INVISIBLE (-6300 5625);
FORCEPROP 1 LASTPIN (-6525 5575) $PN 1
J 0
(-6513 5587);
DISPLAY 0.489362 (-6513 5587);
PAINT MONO (-6513 5587);
FORCEPROP 1 LASTPIN (-6325 5575) $PN 2
J 0
(-6363 5587);
DISPLAY 0.489362 (-6363 5587);
PAINT MONO (-6363 5587);
FORCEPROP 1 LAST VALUE 0
J 2
(-6550 5575);
DISPLAY 0.489362 (-6550 5575);
PAINT SKYBLUE (-6550 5575);
FORCEPROP 2 LAST ROOM RST_CPU0_PLD_TO_DIMM
J 2
(-6400 5675);
DISPLAY 0.744681 (-6400 5675);
PAINT RED (-6400 5675);
DISPLAY INVISIBLE (-6400 5675);
FORCEPROP 1 LAST PACK_TYPE 0402LF
J 2
(-6250 5500);
DISPLAY 0.489362 (-6250 5500);
PAINT SKYBLUE (-6250 5500);
DISPLAY INVISIBLE (-6250 5500);
FORCEPROP 1 LAST PART_NUMBER CS00002JB38
J 2
(-6325 5625);
DISPLAY 0.489362 (-6325 5625);
PAINT SKYBLUE (-6325 5625);
DISPLAY INVISIBLE (-6325 5625);
FORCEPROP 1 LAST TOLERANCE 5%
J 0
(-6550 5550);
DISPLAY 0.489362 (-6550 5550);
PAINT SKYBLUE (-6550 5550);
DISPLAY INVISIBLE (-6550 5550);
FORCEPROP 1 LAST MATERIAL CHIP
J 2
(-6250 5550);
DISPLAY 0.489362 (-6250 5550);
PAINT SKYBLUE (-6250 5550);
DISPLAY INVISIBLE (-6250 5550);
FORCEPROP 1 LAST WATTAGE 1/16W
J 2
(-6500 5500);
DISPLAY 0.489362 (-6500 5500);
PAINT SKYBLUE (-6500 5500);
DISPLAY INVISIBLE (-6500 5500);
FORCEPROP 1 LAST PATH I749
J 0
(-6475 5725);
DISPLAY 0.978723 (-6475 5725);
PAINT WHITE (-6475 5725);
DISPLAY INVISIBLE (-6475 5725);
FORCEPROP 2 LAST CDS_LIB pure_quanta
J 2
(-6425 5575);
DISPLAY INVISIBLE (-6425 5575);
FORCEPROP 2 LAST BOM_COST MEM
J 2
(-6400 5725);
DISPLAY 0.744681 (-6400 5725);
PAINT WHITE (-6400 5725);
DISPLAY INVISIBLE (-6400 5725);
FORCEADD Q_RES..1
(-6425 5425);
FORCEPROP 1 LAST LOCATION R188
J 0
(-6300 5425);
DISPLAY 0.489362 (-6300 5425);
PAINT SKYBLUE (-6300 5425);
FORCEPROP 0 LAST $SEC 1
J 2
(-6300 5475);
DISPLAY 0.680851 (-6300 5475);
PAINT MONO (-6300 5475);
DISPLAY INVISIBLE (-6300 5475);
FORCEPROP 0 LAST CDS_SEC 1
J 2
(-6300 5475);
DISPLAY 1.021277 (-6300 5475);
DISPLAY INVISIBLE (-6300 5475);
FORCEPROP 1 LASTPIN (-6525 5425) $PN 1
J 0
(-6513 5437);
DISPLAY 0.489362 (-6513 5437);
PAINT MONO (-6513 5437);
FORCEPROP 1 LASTPIN (-6325 5425) $PN 2
J 0
(-6363 5437);
DISPLAY 0.489362 (-6363 5437);
PAINT MONO (-6363 5437);
FORCEPROP 1 LAST VALUE 0
J 2
(-6550 5425);
DISPLAY 0.489362 (-6550 5425);
PAINT SKYBLUE (-6550 5425);
FORCEPROP 2 LAST ROOM RST_CPU0_PLD_TO_DIMM
J 2
(-6400 5525);
DISPLAY 0.744681 (-6400 5525);
PAINT RED (-6400 5525);
DISPLAY INVISIBLE (-6400 5525);
FORCEPROP 1 LAST PACK_TYPE 0402LF
J 2
(-6250 5350);
DISPLAY 0.489362 (-6250 5350);
PAINT SKYBLUE (-6250 5350);
DISPLAY INVISIBLE (-6250 5350);
FORCEPROP 1 LAST PART_NUMBER CS00002JB38
J 2
(-6325 5475);
DISPLAY 0.489362 (-6325 5475);
PAINT SKYBLUE (-6325 5475);
DISPLAY INVISIBLE (-6325 5475);
FORCEPROP 1 LAST TOLERANCE 5%
J 0
(-6550 5400);
DISPLAY 0.489362 (-6550 5400);
PAINT SKYBLUE (-6550 5400);
DISPLAY INVISIBLE (-6550 5400);
FORCEPROP 1 LAST MATERIAL CHIP
J 2
(-6250 5400);
DISPLAY 0.489362 (-6250 5400);
PAINT SKYBLUE (-6250 5400);
DISPLAY INVISIBLE (-6250 5400);
FORCEPROP 1 LAST WATTAGE 1/16W
J 2
(-6500 5350);
DISPLAY 0.489362 (-6500 5350);
PAINT SKYBLUE (-6500 5350);
DISPLAY INVISIBLE (-6500 5350);
FORCEPROP 1 LAST PATH I750
J 0
(-6475 5575);
DISPLAY 0.978723 (-6475 5575);
PAINT WHITE (-6475 5575);
DISPLAY INVISIBLE (-6475 5575);
FORCEPROP 2 LAST BOM_COST MEM
J 2
(-6400 5575);
DISPLAY 0.744681 (-6400 5575);
PAINT WHITE (-6400 5575);
DISPLAY INVISIBLE (-6400 5575);
FORCEPROP 2 LAST CDS_LIB pure_quanta
J 2
(-6425 5425);
DISPLAY INVISIBLE (-6425 5425);
FORCEADD Q_RES..1
(-6425 5525);
FORCEPROP 1 LAST LOCATION R190
J 0
(-6300 5525);
DISPLAY 0.489362 (-6300 5525);
PAINT SKYBLUE (-6300 5525);
FORCEPROP 0 LAST $SEC 1
J 2
(-6300 5575);
DISPLAY 0.680851 (-6300 5575);
PAINT MONO (-6300 5575);
DISPLAY INVISIBLE (-6300 5575);
FORCEPROP 0 LAST CDS_SEC 1
J 2
(-6300 5575);
DISPLAY 1.021277 (-6300 5575);
DISPLAY INVISIBLE (-6300 5575);
FORCEPROP 1 LASTPIN (-6525 5525) $PN 1
J 0
(-6513 5537);
DISPLAY 0.489362 (-6513 5537);
PAINT MONO (-6513 5537);
FORCEPROP 1 LASTPIN (-6325 5525) $PN 2
J 0
(-6363 5537);
DISPLAY 0.489362 (-6363 5537);
PAINT MONO (-6363 5537);
FORCEPROP 1 LAST VALUE 0
J 2
(-6550 5525);
DISPLAY 0.489362 (-6550 5525);
PAINT SKYBLUE (-6550 5525);
FORCEPROP 2 LAST ROOM RST_CPU0_PLD_TO_DIMM
J 2
(-6400 5625);
DISPLAY 0.744681 (-6400 5625);
PAINT RED (-6400 5625);
DISPLAY INVISIBLE (-6400 5625);
FORCEPROP 1 LAST PACK_TYPE 0402LF
J 2
(-6250 5450);
DISPLAY 0.489362 (-6250 5450);
PAINT SKYBLUE (-6250 5450);
DISPLAY INVISIBLE (-6250 5450);
FORCEPROP 1 LAST PART_NUMBER CS00002JB38
J 2
(-6325 5575);
DISPLAY 0.489362 (-6325 5575);
PAINT SKYBLUE (-6325 5575);
DISPLAY INVISIBLE (-6325 5575);
FORCEPROP 1 LAST TOLERANCE 5%
J 0
(-6550 5500);
DISPLAY 0.489362 (-6550 5500);
PAINT SKYBLUE (-6550 5500);
DISPLAY INVISIBLE (-6550 5500);
FORCEPROP 1 LAST MATERIAL CHIP
J 2
(-6250 5500);
DISPLAY 0.489362 (-6250 5500);
PAINT SKYBLUE (-6250 5500);
DISPLAY INVISIBLE (-6250 5500);
FORCEPROP 1 LAST WATTAGE 1/16W
J 2
(-6500 5450);
DISPLAY 0.489362 (-6500 5450);
PAINT SKYBLUE (-6500 5450);
DISPLAY INVISIBLE (-6500 5450);
FORCEPROP 1 LAST PATH I751
J 0
(-6475 5675);
DISPLAY 0.978723 (-6475 5675);
PAINT WHITE (-6475 5675);
DISPLAY INVISIBLE (-6475 5675);
FORCEPROP 2 LAST BOM_COST MEM
J 2
(-6400 5675);
DISPLAY 0.744681 (-6400 5675);
PAINT WHITE (-6400 5675);
DISPLAY INVISIBLE (-6400 5675);
FORCEPROP 2 LAST CDS_LIB pure_quanta
J 2
(-6425 5525);
DISPLAY INVISIBLE (-6425 5525);
FORCEADD Q_RES..1
(-6425 5475);
FORCEPROP 1 LAST LOCATION R239
J 0
(-6300 5475);
DISPLAY 0.489362 (-6300 5475);
PAINT SKYBLUE (-6300 5475);
FORCEPROP 0 LAST $SEC 1
J 2
(-6300 5525);
DISPLAY 0.680851 (-6300 5525);
PAINT MONO (-6300 5525);
DISPLAY INVISIBLE (-6300 5525);
FORCEPROP 0 LAST CDS_SEC 1
J 2
(-6300 5525);
DISPLAY 1.021277 (-6300 5525);
DISPLAY INVISIBLE (-6300 5525);
FORCEPROP 1 LASTPIN (-6525 5475) $PN 1
J 0
(-6513 5487);
DISPLAY 0.489362 (-6513 5487);
PAINT MONO (-6513 5487);
FORCEPROP 1 LASTPIN (-6325 5475) $PN 2
J 0
(-6363 5487);
DISPLAY 0.489362 (-6363 5487);
PAINT MONO (-6363 5487);
FORCEPROP 1 LAST VALUE 0
J 2
(-6550 5475);
DISPLAY 0.489362 (-6550 5475);
PAINT SKYBLUE (-6550 5475);
FORCEPROP 2 LAST ROOM RST_CPU0_PLD_TO_DIMM
J 2
(-6400 5575);
DISPLAY 0.744681 (-6400 5575);
PAINT RED (-6400 5575);
DISPLAY INVISIBLE (-6400 5575);
FORCEPROP 1 LAST PACK_TYPE 0402LF
J 2
(-6250 5400);
DISPLAY 0.489362 (-6250 5400);
PAINT SKYBLUE (-6250 5400);
DISPLAY INVISIBLE (-6250 5400);
FORCEPROP 1 LAST PART_NUMBER CS00002JB38
J 2
(-6325 5525);
DISPLAY 0.489362 (-6325 5525);
PAINT SKYBLUE (-6325 5525);
DISPLAY INVISIBLE (-6325 5525);
FORCEPROP 1 LAST TOLERANCE 5%
J 0
(-6550 5450);
DISPLAY 0.489362 (-6550 5450);
PAINT SKYBLUE (-6550 5450);
DISPLAY INVISIBLE (-6550 5450);
FORCEPROP 1 LAST MATERIAL CHIP
J 2
(-6250 5450);
DISPLAY 0.489362 (-6250 5450);
PAINT SKYBLUE (-6250 5450);
DISPLAY INVISIBLE (-6250 5450);
FORCEPROP 1 LAST WATTAGE 1/16W
J 2
(-6500 5400);
DISPLAY 0.489362 (-6500 5400);
PAINT SKYBLUE (-6500 5400);
DISPLAY INVISIBLE (-6500 5400);
FORCEPROP 1 LAST PATH I752
J 0
(-6475 5625);
DISPLAY 0.978723 (-6475 5625);
PAINT WHITE (-6475 5625);
DISPLAY INVISIBLE (-6475 5625);
FORCEPROP 2 LAST BOM_COST MEM
J 2
(-6400 5625);
DISPLAY 0.744681 (-6400 5625);
PAINT WHITE (-6400 5625);
DISPLAY INVISIBLE (-6400 5625);
FORCEPROP 2 LAST CDS_LIB pure_quanta
J 2
(-6425 5475);
DISPLAY INVISIBLE (-6425 5475);
FORCEADD Q_RES..1
(-6425 5325);
FORCEPROP 1 LAST LOCATION R231
J 0
(-6300 5325);
DISPLAY 0.489362 (-6300 5325);
PAINT SKYBLUE (-6300 5325);
FORCEPROP 0 LAST $SEC 1
J 0
(-6300 5375);
DISPLAY 0.680851 (-6300 5375);
PAINT MONO (-6300 5375);
DISPLAY INVISIBLE (-6300 5375);
FORCEPROP 0 LAST CDS_SEC 1
J 0
(-6300 5375);
DISPLAY 1.021277 (-6300 5375);
DISPLAY INVISIBLE (-6300 5375);
FORCEPROP 1 LASTPIN (-6525 5325) $PN 1
J 0
(-6513 5337);
DISPLAY 0.489362 (-6513 5337);
PAINT MONO (-6513 5337);
FORCEPROP 1 LASTPIN (-6325 5325) $PN 2
J 0
(-6363 5337);
DISPLAY 0.489362 (-6363 5337);
PAINT MONO (-6363 5337);
FORCEPROP 1 LAST VALUE 0
J 2
(-6550 5325);
DISPLAY 0.489362 (-6550 5325);
PAINT SKYBLUE (-6550 5325);
FORCEPROP 2 LAST ROOM RST_CPU0_PLD_TO_DIMM
J 2
(-6400 5425);
DISPLAY 0.744681 (-6400 5425);
PAINT RED (-6400 5425);
DISPLAY INVISIBLE (-6400 5425);
FORCEPROP 1 LAST PACK_TYPE 0402LF
J 2
(-6250 5250);
DISPLAY 0.489362 (-6250 5250);
PAINT SKYBLUE (-6250 5250);
DISPLAY INVISIBLE (-6250 5250);
FORCEPROP 1 LAST PART_NUMBER CS00002JB38
J 2
(-6325 5375);
DISPLAY 0.489362 (-6325 5375);
PAINT SKYBLUE (-6325 5375);
DISPLAY INVISIBLE (-6325 5375);
FORCEPROP 1 LAST TOLERANCE 5%
J 0
(-6550 5300);
DISPLAY 0.489362 (-6550 5300);
PAINT SKYBLUE (-6550 5300);
DISPLAY INVISIBLE (-6550 5300);
FORCEPROP 1 LAST MATERIAL CHIP
J 2
(-6250 5300);
DISPLAY 0.489362 (-6250 5300);
PAINT SKYBLUE (-6250 5300);
DISPLAY INVISIBLE (-6250 5300);
FORCEPROP 1 LAST WATTAGE 1/16W
J 2
(-6500 5250);
DISPLAY 0.489362 (-6500 5250);
PAINT SKYBLUE (-6500 5250);
DISPLAY INVISIBLE (-6500 5250);
FORCEPROP 1 LAST PATH I753
J 0
(-6475 5475);
DISPLAY 0.978723 (-6475 5475);
PAINT WHITE (-6475 5475);
DISPLAY INVISIBLE (-6475 5475);
FORCEPROP 2 LAST BOM_COST MEM
J 2
(-6400 5475);
DISPLAY 0.744681 (-6400 5475);
PAINT WHITE (-6400 5475);
DISPLAY INVISIBLE (-6400 5475);
FORCEPROP 2 LAST CDS_LIB pure_quanta
J 2
(-6425 5325);
DISPLAY INVISIBLE (-6425 5325);
FORCEADD Q_RES..1
(-6425 5375);
FORCEPROP 1 LAST LOCATION R189
J 0
(-6300 5375);
DISPLAY 0.489362 (-6300 5375);
PAINT SKYBLUE (-6300 5375);
FORCEPROP 0 LAST $SEC 1
J 2
(-6300 5425);
DISPLAY 0.680851 (-6300 5425);
PAINT MONO (-6300 5425);
DISPLAY INVISIBLE (-6300 5425);
FORCEPROP 0 LAST CDS_SEC 1
J 2
(-6300 5425);
DISPLAY 1.021277 (-6300 5425);
DISPLAY INVISIBLE (-6300 5425);
FORCEPROP 1 LASTPIN (-6525 5375) $PN 1
J 0
(-6513 5387);
DISPLAY 0.489362 (-6513 5387);
PAINT MONO (-6513 5387);
FORCEPROP 1 LASTPIN (-6325 5375) $PN 2
J 0
(-6363 5387);
DISPLAY 0.489362 (-6363 5387);
PAINT MONO (-6363 5387);
FORCEPROP 1 LAST VALUE 0
J 2
(-6550 5375);
DISPLAY 0.489362 (-6550 5375);
PAINT SKYBLUE (-6550 5375);
FORCEPROP 2 LAST ROOM RST_CPU0_PLD_TO_DIMM
J 2
(-6400 5475);
DISPLAY 0.744681 (-6400 5475);
PAINT RED (-6400 5475);
DISPLAY INVISIBLE (-6400 5475);
FORCEPROP 1 LAST PACK_TYPE 0402LF
J 2
(-6250 5300);
DISPLAY 0.489362 (-6250 5300);
PAINT SKYBLUE (-6250 5300);
DISPLAY INVISIBLE (-6250 5300);
FORCEPROP 1 LAST PART_NUMBER CS00002JB38
J 2
(-6325 5425);
DISPLAY 0.489362 (-6325 5425);
PAINT SKYBLUE (-6325 5425);
DISPLAY INVISIBLE (-6325 5425);
FORCEPROP 1 LAST TOLERANCE 5%
J 0
(-6550 5350);
DISPLAY 0.489362 (-6550 5350);
PAINT SKYBLUE (-6550 5350);
DISPLAY INVISIBLE (-6550 5350);
FORCEPROP 1 LAST MATERIAL CHIP
J 2
(-6250 5350);
DISPLAY 0.489362 (-6250 5350);
PAINT SKYBLUE (-6250 5350);
DISPLAY INVISIBLE (-6250 5350);
FORCEPROP 1 LAST WATTAGE 1/16W
J 2
(-6500 5300);
DISPLAY 0.489362 (-6500 5300);
PAINT SKYBLUE (-6500 5300);
DISPLAY INVISIBLE (-6500 5300);
FORCEPROP 1 LAST PATH I754
J 0
(-6475 5525);
DISPLAY 0.978723 (-6475 5525);
PAINT WHITE (-6475 5525);
DISPLAY INVISIBLE (-6475 5525);
FORCEPROP 2 LAST BOM_COST MEM
J 2
(-6400 5525);
DISPLAY 0.744681 (-6400 5525);
PAINT WHITE (-6400 5525);
DISPLAY INVISIBLE (-6400 5525);
FORCEPROP 2 LAST CDS_LIB pure_quanta
J 2
(-6425 5375);
DISPLAY INVISIBLE (-6425 5375);
FORCEADD Q_RES..1
(-6425 5275);
FORCEPROP 1 LAST LOCATION R137
J 0
(-6300 5275);
DISPLAY 0.489362 (-6300 5275);
PAINT SKYBLUE (-6300 5275);
FORCEPROP 0 LAST $SEC 1
J 0
(-6300 5325);
DISPLAY 0.680851 (-6300 5325);
PAINT MONO (-6300 5325);
DISPLAY INVISIBLE (-6300 5325);
FORCEPROP 0 LAST CDS_SEC 1
J 0
(-6300 5325);
DISPLAY 1.021277 (-6300 5325);
DISPLAY INVISIBLE (-6300 5325);
FORCEPROP 1 LASTPIN (-6525 5275) $PN 1
J 0
(-6513 5287);
DISPLAY 0.489362 (-6513 5287);
PAINT MONO (-6513 5287);
FORCEPROP 1 LASTPIN (-6325 5275) $PN 2
J 0
(-6363 5287);
DISPLAY 0.489362 (-6363 5287);
PAINT MONO (-6363 5287);
FORCEPROP 1 LAST VALUE 0
J 2
(-6550 5275);
DISPLAY 0.489362 (-6550 5275);
PAINT SKYBLUE (-6550 5275);
FORCEPROP 2 LAST ROOM RST_CPU0_PLD_TO_DIMM
J 2
(-6400 5375);
DISPLAY 0.744681 (-6400 5375);
PAINT RED (-6400 5375);
DISPLAY INVISIBLE (-6400 5375);
FORCEPROP 1 LAST PACK_TYPE 0402LF
J 2
(-6250 5200);
DISPLAY 0.489362 (-6250 5200);
PAINT SKYBLUE (-6250 5200);
DISPLAY INVISIBLE (-6250 5200);
FORCEPROP 1 LAST PART_NUMBER CS00002JB38
J 2
(-6325 5325);
DISPLAY 0.489362 (-6325 5325);
PAINT SKYBLUE (-6325 5325);
DISPLAY INVISIBLE (-6325 5325);
FORCEPROP 1 LAST TOLERANCE 5%
J 0
(-6550 5250);
DISPLAY 0.489362 (-6550 5250);
PAINT SKYBLUE (-6550 5250);
DISPLAY INVISIBLE (-6550 5250);
FORCEPROP 1 LAST MATERIAL CHIP
J 2
(-6250 5250);
DISPLAY 0.489362 (-6250 5250);
PAINT SKYBLUE (-6250 5250);
DISPLAY INVISIBLE (-6250 5250);
FORCEPROP 1 LAST WATTAGE 1/16W
J 2
(-6500 5200);
DISPLAY 0.489362 (-6500 5200);
PAINT SKYBLUE (-6500 5200);
DISPLAY INVISIBLE (-6500 5200);
FORCEPROP 1 LAST PATH I755
J 0
(-6475 5425);
DISPLAY 0.978723 (-6475 5425);
PAINT WHITE (-6475 5425);
DISPLAY INVISIBLE (-6475 5425);
FORCEPROP 2 LAST CDS_LIB pure_quanta
J 2
(-6425 5275);
DISPLAY INVISIBLE (-6425 5275);
FORCEPROP 2 LAST BOM_COST MEM
J 2
(-6400 5425);
DISPLAY 0.744681 (-6400 5425);
PAINT WHITE (-6400 5425);
DISPLAY INVISIBLE (-6400 5425);
FORCEADD Q_RES..1
(-6425 5225);
FORCEPROP 1 LAST LOCATION R141
J 0
(-6300 5225);
DISPLAY 0.489362 (-6300 5225);
PAINT SKYBLUE (-6300 5225);
FORCEPROP 0 LAST $SEC 1
J 0
(-6300 5275);
DISPLAY 0.680851 (-6300 5275);
PAINT MONO (-6300 5275);
DISPLAY INVISIBLE (-6300 5275);
FORCEPROP 0 LAST CDS_SEC 1
J 0
(-6300 5275);
DISPLAY 1.021277 (-6300 5275);
DISPLAY INVISIBLE (-6300 5275);
FORCEPROP 1 LASTPIN (-6525 5225) $PN 1
J 0
(-6513 5237);
DISPLAY 0.489362 (-6513 5237);
PAINT MONO (-6513 5237);
FORCEPROP 1 LASTPIN (-6325 5225) $PN 2
J 0
(-6363 5237);
DISPLAY 0.489362 (-6363 5237);
PAINT MONO (-6363 5237);
FORCEPROP 1 LAST VALUE 0
J 2
(-6550 5225);
DISPLAY 0.489362 (-6550 5225);
PAINT SKYBLUE (-6550 5225);
FORCEPROP 2 LAST ROOM RST_CPU0_PLD_TO_DIMM
J 2
(-6400 5325);
DISPLAY 0.744681 (-6400 5325);
PAINT RED (-6400 5325);
DISPLAY INVISIBLE (-6400 5325);
FORCEPROP 1 LAST PACK_TYPE 0402LF
J 2
(-6250 5150);
DISPLAY 0.489362 (-6250 5150);
PAINT SKYBLUE (-6250 5150);
DISPLAY INVISIBLE (-6250 5150);
FORCEPROP 1 LAST PART_NUMBER CS00002JB38
J 2
(-6325 5275);
DISPLAY 0.489362 (-6325 5275);
PAINT SKYBLUE (-6325 5275);
DISPLAY INVISIBLE (-6325 5275);
FORCEPROP 1 LAST TOLERANCE 5%
J 0
(-6550 5200);
DISPLAY 0.489362 (-6550 5200);
PAINT SKYBLUE (-6550 5200);
DISPLAY INVISIBLE (-6550 5200);
FORCEPROP 1 LAST MATERIAL CHIP
J 2
(-6250 5200);
DISPLAY 0.489362 (-6250 5200);
PAINT SKYBLUE (-6250 5200);
DISPLAY INVISIBLE (-6250 5200);
FORCEPROP 1 LAST WATTAGE 1/16W
J 2
(-6500 5150);
DISPLAY 0.489362 (-6500 5150);
PAINT SKYBLUE (-6500 5150);
DISPLAY INVISIBLE (-6500 5150);
FORCEPROP 1 LAST PATH I756
J 0
(-6475 5375);
DISPLAY 0.978723 (-6475 5375);
PAINT WHITE (-6475 5375);
DISPLAY INVISIBLE (-6475 5375);
FORCEPROP 2 LAST BOM_COST MEM
J 2
(-6400 5375);
DISPLAY 0.744681 (-6400 5375);
PAINT WHITE (-6400 5375);
DISPLAY INVISIBLE (-6400 5375);
FORCEPROP 2 LAST CDS_LIB pure_quanta
J 2
(-6425 5225);
DISPLAY INVISIBLE (-6425 5225);
FORCEADD Q_RES..1
(-6425 5025);
FORCEPROP 1 LAST LOCATION R269
J 0
(-6300 5025);
DISPLAY 0.489362 (-6300 5025);
PAINT SKYBLUE (-6300 5025);
FORCEPROP 0 LAST $SEC 1
J 0
(-6300 5075);
DISPLAY 0.680851 (-6300 5075);
PAINT MONO (-6300 5075);
DISPLAY INVISIBLE (-6300 5075);
FORCEPROP 0 LAST CDS_SEC 1
J 0
(-6300 5075);
DISPLAY 1.021277 (-6300 5075);
DISPLAY INVISIBLE (-6300 5075);
FORCEPROP 1 LASTPIN (-6525 5025) $PN 1
J 0
(-6513 5037);
DISPLAY 0.489362 (-6513 5037);
PAINT MONO (-6513 5037);
FORCEPROP 1 LASTPIN (-6325 5025) $PN 2
J 0
(-6363 5037);
DISPLAY 0.489362 (-6363 5037);
PAINT MONO (-6363 5037);
FORCEPROP 1 LAST VALUE 0
J 2
(-6550 5025);
DISPLAY 0.489362 (-6550 5025);
PAINT SKYBLUE (-6550 5025);
FORCEPROP 2 LAST ROOM RST_CPU0_PLD_TO_DIMM
J 2
(-6400 5125);
DISPLAY 0.744681 (-6400 5125);
PAINT RED (-6400 5125);
DISPLAY INVISIBLE (-6400 5125);
FORCEPROP 1 LAST PACK_TYPE 0402LF
J 2
(-6250 4950);
DISPLAY 0.489362 (-6250 4950);
PAINT SKYBLUE (-6250 4950);
DISPLAY INVISIBLE (-6250 4950);
FORCEPROP 1 LAST PART_NUMBER CS00002JB38
J 2
(-6325 5075);
DISPLAY 0.489362 (-6325 5075);
PAINT SKYBLUE (-6325 5075);
DISPLAY INVISIBLE (-6325 5075);
FORCEPROP 1 LAST TOLERANCE 5%
J 0
(-6550 5000);
DISPLAY 0.489362 (-6550 5000);
PAINT SKYBLUE (-6550 5000);
DISPLAY INVISIBLE (-6550 5000);
FORCEPROP 1 LAST MATERIAL CHIP
J 2
(-6250 5000);
DISPLAY 0.489362 (-6250 5000);
PAINT SKYBLUE (-6250 5000);
DISPLAY INVISIBLE (-6250 5000);
FORCEPROP 1 LAST WATTAGE 1/16W
J 2
(-6500 4950);
DISPLAY 0.489362 (-6500 4950);
PAINT SKYBLUE (-6500 4950);
DISPLAY INVISIBLE (-6500 4950);
FORCEPROP 1 LAST PATH I758
J 0
(-6475 5175);
DISPLAY 0.978723 (-6475 5175);
PAINT WHITE (-6475 5175);
DISPLAY INVISIBLE (-6475 5175);
FORCEPROP 2 LAST BOM_COST MEM
J 2
(-6400 5175);
DISPLAY 0.744681 (-6400 5175);
PAINT WHITE (-6400 5175);
DISPLAY INVISIBLE (-6400 5175);
FORCEPROP 2 LAST CDS_LIB pure_quanta
J 2
(-6425 5025);
DISPLAY INVISIBLE (-6425 5025);
FORCEADD Q_RES..1
(-6425 4925);
FORCEPROP 1 LAST LOCATION R233
J 0
(-6300 4925);
DISPLAY 0.489362 (-6300 4925);
PAINT SKYBLUE (-6300 4925);
FORCEPROP 0 LAST $SEC 1
J 0
(-6300 4975);
DISPLAY 0.680851 (-6300 4975);
PAINT MONO (-6300 4975);
DISPLAY INVISIBLE (-6300 4975);
FORCEPROP 0 LAST CDS_SEC 1
J 0
(-6300 4975);
DISPLAY 1.021277 (-6300 4975);
DISPLAY INVISIBLE (-6300 4975);
FORCEPROP 1 LASTPIN (-6525 4925) $PN 1
J 0
(-6513 4937);
DISPLAY 0.489362 (-6513 4937);
PAINT MONO (-6513 4937);
FORCEPROP 1 LASTPIN (-6325 4925) $PN 2
J 0
(-6363 4937);
DISPLAY 0.489362 (-6363 4937);
PAINT MONO (-6363 4937);
FORCEPROP 1 LAST VALUE 0
J 2
(-6550 4925);
DISPLAY 0.489362 (-6550 4925);
PAINT SKYBLUE (-6550 4925);
FORCEPROP 2 LAST ROOM RST_CPU0_PLD_TO_DIMM
J 2
(-6400 5025);
DISPLAY 0.744681 (-6400 5025);
PAINT RED (-6400 5025);
DISPLAY INVISIBLE (-6400 5025);
FORCEPROP 1 LAST PACK_TYPE 0402LF
J 2
(-6250 4850);
DISPLAY 0.489362 (-6250 4850);
PAINT SKYBLUE (-6250 4850);
DISPLAY INVISIBLE (-6250 4850);
FORCEPROP 1 LAST PART_NUMBER CS00002JB38
J 2
(-6325 4975);
DISPLAY 0.489362 (-6325 4975);
PAINT SKYBLUE (-6325 4975);
DISPLAY INVISIBLE (-6325 4975);
FORCEPROP 1 LAST TOLERANCE 5%
J 0
(-6550 4900);
DISPLAY 0.489362 (-6550 4900);
PAINT SKYBLUE (-6550 4900);
DISPLAY INVISIBLE (-6550 4900);
FORCEPROP 1 LAST MATERIAL CHIP
J 2
(-6250 4900);
DISPLAY 0.489362 (-6250 4900);
PAINT SKYBLUE (-6250 4900);
DISPLAY INVISIBLE (-6250 4900);
FORCEPROP 1 LAST WATTAGE 1/16W
J 2
(-6500 4850);
DISPLAY 0.489362 (-6500 4850);
PAINT SKYBLUE (-6500 4850);
DISPLAY INVISIBLE (-6500 4850);
FORCEPROP 1 LAST PATH I759
J 0
(-6475 5075);
DISPLAY 0.978723 (-6475 5075);
PAINT WHITE (-6475 5075);
DISPLAY INVISIBLE (-6475 5075);
FORCEPROP 2 LAST CDS_LIB pure_quanta
J 2
(-6425 4925);
DISPLAY INVISIBLE (-6425 4925);
FORCEPROP 2 LAST BOM_COST MEM
J 2
(-6400 5075);
DISPLAY 0.744681 (-6400 5075);
PAINT WHITE (-6400 5075);
DISPLAY INVISIBLE (-6400 5075);
FORCEADD Q_RES..1
(-6425 4975);
FORCEPROP 1 LAST LOCATION R268
J 0
(-6300 4975);
DISPLAY 0.489362 (-6300 4975);
PAINT SKYBLUE (-6300 4975);
FORCEPROP 0 LAST $SEC 1
J 0
(-6300 5025);
DISPLAY 0.680851 (-6300 5025);
PAINT MONO (-6300 5025);
DISPLAY INVISIBLE (-6300 5025);
FORCEPROP 0 LAST CDS_SEC 1
J 0
(-6300 5025);
DISPLAY 1.021277 (-6300 5025);
DISPLAY INVISIBLE (-6300 5025);
FORCEPROP 1 LASTPIN (-6525 4975) $PN 1
J 0
(-6513 4987);
DISPLAY 0.489362 (-6513 4987);
PAINT MONO (-6513 4987);
FORCEPROP 1 LASTPIN (-6325 4975) $PN 2
J 0
(-6363 4987);
DISPLAY 0.489362 (-6363 4987);
PAINT MONO (-6363 4987);
FORCEPROP 1 LAST VALUE 0
J 2
(-6550 4975);
DISPLAY 0.489362 (-6550 4975);
PAINT SKYBLUE (-6550 4975);
FORCEPROP 2 LAST ROOM RST_CPU0_PLD_TO_DIMM
J 2
(-6400 5075);
DISPLAY 0.744681 (-6400 5075);
PAINT RED (-6400 5075);
DISPLAY INVISIBLE (-6400 5075);
FORCEPROP 1 LAST PACK_TYPE 0402LF
J 2
(-6250 4900);
DISPLAY 0.489362 (-6250 4900);
PAINT SKYBLUE (-6250 4900);
DISPLAY INVISIBLE (-6250 4900);
FORCEPROP 1 LAST PART_NUMBER CS00002JB38
J 2
(-6325 5025);
DISPLAY 0.489362 (-6325 5025);
PAINT SKYBLUE (-6325 5025);
DISPLAY INVISIBLE (-6325 5025);
FORCEPROP 1 LAST TOLERANCE 5%
J 0
(-6550 4950);
DISPLAY 0.489362 (-6550 4950);
PAINT SKYBLUE (-6550 4950);
DISPLAY INVISIBLE (-6550 4950);
FORCEPROP 1 LAST MATERIAL CHIP
J 2
(-6250 4950);
DISPLAY 0.489362 (-6250 4950);
PAINT SKYBLUE (-6250 4950);
DISPLAY INVISIBLE (-6250 4950);
FORCEPROP 1 LAST WATTAGE 1/16W
J 2
(-6500 4900);
DISPLAY 0.489362 (-6500 4900);
PAINT SKYBLUE (-6500 4900);
DISPLAY INVISIBLE (-6500 4900);
FORCEPROP 1 LAST PATH I760
J 0
(-6475 5125);
DISPLAY 0.978723 (-6475 5125);
PAINT WHITE (-6475 5125);
DISPLAY INVISIBLE (-6475 5125);
FORCEPROP 2 LAST CDS_LIB pure_quanta
J 2
(-6425 4975);
DISPLAY INVISIBLE (-6425 4975);
FORCEPROP 2 LAST BOM_COST MEM
J 2
(-6400 5125);
DISPLAY 0.744681 (-6400 5125);
PAINT WHITE (-6400 5125);
DISPLAY INVISIBLE (-6400 5125);
FORCEADD OFFPAGE..6
(-7275 6175);
FORCEPROP 2 LAST $XR0 54 
J 0
(-7554 6175);
DISPLAY 0.638298 (-7554 6175);
PAINT MONO (-7554 6175);
FORCEPROP 1 LAST OFFPAGE TRUE
J 0
(-6950 6050);
DISPLAY 0.872340 (-6950 6050);
PAINT GREEN (-6950 6050);
DISPLAY INVISIBLE (-6950 6050);
FORCEPROP 1 LAST COMMENT_BODY TRUE
J 0
(-7175 6100);
DISPLAY 0.872340 (-7175 6100);
PAINT GREEN (-7175 6100);
DISPLAY INVISIBLE (-7175 6100);
FORCEPROP 2 LAST CDS_LIB standard
J 0
(-7275 6175);
DISPLAY INVISIBLE (-7275 6175);
FORCEPROP 2 LAST PATH I761
J 0
(-7225 6250);
DISPLAY 0.680851 (-7225 6250);
DISPLAY INVISIBLE (-7225 6250);
FORCEADD OFFPAGE..6
(-7275 6125);
FORCEPROP 2 LAST $XR0 54 
J 0
(-7554 6125);
DISPLAY 0.638298 (-7554 6125);
PAINT MONO (-7554 6125);
FORCEPROP 1 LAST OFFPAGE TRUE
J 0
(-6950 6000);
DISPLAY 0.872340 (-6950 6000);
PAINT GREEN (-6950 6000);
DISPLAY INVISIBLE (-6950 6000);
FORCEPROP 1 LAST COMMENT_BODY TRUE
J 0
(-7175 6050);
DISPLAY 0.872340 (-7175 6050);
PAINT GREEN (-7175 6050);
DISPLAY INVISIBLE (-7175 6050);
FORCEPROP 2 LAST CDS_LIB standard
J 0
(-7275 6125);
DISPLAY INVISIBLE (-7275 6125);
FORCEPROP 2 LAST PATH I762
J 0
(-7225 6200);
DISPLAY 0.680851 (-7225 6200);
DISPLAY INVISIBLE (-7225 6200);
FORCEADD OFFPAGE..6
(-7275 6075);
FORCEPROP 2 LAST $XR0 54 
J 0
(-7554 6075);
DISPLAY 0.638298 (-7554 6075);
PAINT MONO (-7554 6075);
FORCEPROP 1 LAST OFFPAGE TRUE
J 0
(-6950 5950);
DISPLAY 0.872340 (-6950 5950);
PAINT GREEN (-6950 5950);
DISPLAY INVISIBLE (-6950 5950);
FORCEPROP 1 LAST COMMENT_BODY TRUE
J 0
(-7175 6000);
DISPLAY 0.872340 (-7175 6000);
PAINT GREEN (-7175 6000);
DISPLAY INVISIBLE (-7175 6000);
FORCEPROP 2 LAST CDS_LIB standard
J 0
(-7275 6075);
DISPLAY INVISIBLE (-7275 6075);
FORCEPROP 2 LAST PATH I763
J 0
(-7225 6150);
DISPLAY 0.680851 (-7225 6150);
DISPLAY INVISIBLE (-7225 6150);
FORCEADD OFFPAGE..6
(-7275 5975);
FORCEPROP 2 LAST $XR1 149 
J 0
(-7674 5975);
DISPLAY 0.638298 (-7674 5975);
PAINT MONO (-7674 5975);
FORCEPROP 2 LAST $XR0 27 
J 0
(-7554 5975);
DISPLAY 0.638298 (-7554 5975);
PAINT MONO (-7554 5975);
FORCEPROP 1 LAST OFFPAGE TRUE
J 0
(-6950 5850);
DISPLAY 0.872340 (-6950 5850);
PAINT GREEN (-6950 5850);
DISPLAY INVISIBLE (-6950 5850);
FORCEPROP 1 LAST COMMENT_BODY TRUE
J 0
(-7175 5900);
DISPLAY 0.872340 (-7175 5900);
PAINT GREEN (-7175 5900);
DISPLAY INVISIBLE (-7175 5900);
FORCEPROP 2 LAST CDS_LIB standard
J 0
(-7275 5975);
DISPLAY INVISIBLE (-7275 5975);
FORCEPROP 2 LAST PATH I764
J 0
(-7225 6050);
DISPLAY 0.680851 (-7225 6050);
DISPLAY INVISIBLE (-7225 6050);
FORCEADD OFFPAGE..6
(-7275 5925);
FORCEPROP 2 LAST $XR0 28 
J 0
(-7554 5925);
DISPLAY 0.638298 (-7554 5925);
PAINT MONO (-7554 5925);
FORCEPROP 1 LAST OFFPAGE TRUE
J 0
(-6950 5800);
DISPLAY 0.872340 (-6950 5800);
PAINT GREEN (-6950 5800);
DISPLAY INVISIBLE (-6950 5800);
FORCEPROP 1 LAST COMMENT_BODY TRUE
J 0
(-7175 5850);
DISPLAY 0.872340 (-7175 5850);
PAINT GREEN (-7175 5850);
DISPLAY INVISIBLE (-7175 5850);
FORCEPROP 2 LAST CDS_LIB standard
J 0
(-7275 5925);
DISPLAY INVISIBLE (-7275 5925);
FORCEPROP 2 LAST PATH I765
J 0
(-7225 6000);
DISPLAY 0.680851 (-7225 6000);
DISPLAY INVISIBLE (-7225 6000);
FORCEADD OFFPAGE..6
(-7275 5825);
FORCEPROP 2 LAST $XR0 55 
J 0
(-7554 5825);
DISPLAY 0.638298 (-7554 5825);
PAINT MONO (-7554 5825);
FORCEPROP 1 LAST OFFPAGE TRUE
J 0
(-6950 5700);
DISPLAY 0.872340 (-6950 5700);
PAINT GREEN (-6950 5700);
DISPLAY INVISIBLE (-6950 5700);
FORCEPROP 1 LAST COMMENT_BODY TRUE
J 0
(-7175 5750);
DISPLAY 0.872340 (-7175 5750);
PAINT GREEN (-7175 5750);
DISPLAY INVISIBLE (-7175 5750);
FORCEPROP 2 LAST CDS_LIB standard
J 0
(-7275 5825);
DISPLAY INVISIBLE (-7275 5825);
FORCEPROP 2 LAST PATH I766
J 0
(-7225 5900);
DISPLAY 0.680851 (-7225 5900);
DISPLAY INVISIBLE (-7225 5900);
FORCEADD OFFPAGE..6
(-7275 5875);
FORCEPROP 2 LAST $XR0 54 
J 0
(-7554 5875);
DISPLAY 0.638298 (-7554 5875);
PAINT MONO (-7554 5875);
FORCEPROP 1 LAST OFFPAGE TRUE
J 0
(-6950 5750);
DISPLAY 0.872340 (-6950 5750);
PAINT GREEN (-6950 5750);
DISPLAY INVISIBLE (-6950 5750);
FORCEPROP 1 LAST COMMENT_BODY TRUE
J 0
(-7175 5800);
DISPLAY 0.872340 (-7175 5800);
PAINT GREEN (-7175 5800);
DISPLAY INVISIBLE (-7175 5800);
FORCEPROP 2 LAST CDS_LIB standard
J 0
(-7275 5875);
DISPLAY INVISIBLE (-7275 5875);
FORCEPROP 2 LAST PATH I767
J 0
(-7225 5950);
DISPLAY 0.680851 (-7225 5950);
DISPLAY INVISIBLE (-7225 5950);
FORCEADD OFFPAGE..6
(-7275 5725);
FORCEPROP 2 LAST $XR0 27 
J 0
(-7554 5725);
DISPLAY 0.638298 (-7554 5725);
PAINT MONO (-7554 5725);
FORCEPROP 1 LAST OFFPAGE TRUE
J 0
(-6950 5600);
DISPLAY 0.872340 (-6950 5600);
PAINT GREEN (-6950 5600);
DISPLAY INVISIBLE (-6950 5600);
FORCEPROP 1 LAST COMMENT_BODY TRUE
J 0
(-7175 5650);
DISPLAY 0.872340 (-7175 5650);
PAINT GREEN (-7175 5650);
DISPLAY INVISIBLE (-7175 5650);
FORCEPROP 2 LAST CDS_LIB standard
J 0
(-7275 5725);
DISPLAY INVISIBLE (-7275 5725);
FORCEPROP 2 LAST PATH I768
J 0
(-7225 5800);
DISPLAY 0.680851 (-7225 5800);
DISPLAY INVISIBLE (-7225 5800);
FORCEADD OFFPAGE..6
(-7275 5775);
FORCEPROP 2 LAST $XR1 149 
J 0
(-7674 5775);
DISPLAY 0.638298 (-7674 5775);
PAINT MONO (-7674 5775);
FORCEPROP 2 LAST $XR0 27 
J 0
(-7554 5775);
DISPLAY 0.638298 (-7554 5775);
PAINT MONO (-7554 5775);
FORCEPROP 1 LAST OFFPAGE TRUE
J 0
(-6950 5650);
DISPLAY 0.872340 (-6950 5650);
PAINT GREEN (-6950 5650);
DISPLAY INVISIBLE (-6950 5650);
FORCEPROP 1 LAST COMMENT_BODY TRUE
J 0
(-7175 5700);
DISPLAY 0.872340 (-7175 5700);
PAINT GREEN (-7175 5700);
DISPLAY INVISIBLE (-7175 5700);
FORCEPROP 2 LAST CDS_LIB standard
J 0
(-7275 5775);
DISPLAY INVISIBLE (-7275 5775);
FORCEPROP 2 LAST PATH I769
J 0
(-7225 5850);
DISPLAY 0.680851 (-7225 5850);
DISPLAY INVISIBLE (-7225 5850);
FORCEADD OFFPAGE..6
(-7275 5675);
FORCEPROP 2 LAST $XR0 28 
J 0
(-7554 5675);
DISPLAY 0.638298 (-7554 5675);
PAINT MONO (-7554 5675);
FORCEPROP 1 LAST OFFPAGE TRUE
J 0
(-6950 5550);
DISPLAY 0.872340 (-6950 5550);
PAINT GREEN (-6950 5550);
DISPLAY INVISIBLE (-6950 5550);
FORCEPROP 1 LAST COMMENT_BODY TRUE
J 0
(-7175 5600);
DISPLAY 0.872340 (-7175 5600);
PAINT GREEN (-7175 5600);
DISPLAY INVISIBLE (-7175 5600);
FORCEPROP 2 LAST CDS_LIB standard
J 0
(-7275 5675);
DISPLAY INVISIBLE (-7275 5675);
FORCEPROP 2 LAST PATH I770
J 0
(-7225 5750);
DISPLAY 0.680851 (-7225 5750);
DISPLAY INVISIBLE (-7225 5750);
FORCEADD OFFPAGE..6
(-7275 5575);
FORCEPROP 2 LAST $XR0 28 
J 0
(-7554 5575);
DISPLAY 0.638298 (-7554 5575);
PAINT MONO (-7554 5575);
FORCEPROP 1 LAST OFFPAGE TRUE
J 0
(-6950 5450);
DISPLAY 0.872340 (-6950 5450);
PAINT GREEN (-6950 5450);
DISPLAY INVISIBLE (-6950 5450);
FORCEPROP 1 LAST COMMENT_BODY TRUE
J 0
(-7175 5500);
DISPLAY 0.872340 (-7175 5500);
PAINT GREEN (-7175 5500);
DISPLAY INVISIBLE (-7175 5500);
FORCEPROP 2 LAST CDS_LIB standard
J 0
(-7275 5575);
DISPLAY INVISIBLE (-7275 5575);
FORCEPROP 2 LAST PATH I771
J 0
(-7225 5650);
DISPLAY 0.680851 (-7225 5650);
DISPLAY INVISIBLE (-7225 5650);
FORCEADD OFFPAGE..6
(-7275 5625);
FORCEPROP 2 LAST $XR0 28 
J 0
(-7554 5625);
DISPLAY 0.638298 (-7554 5625);
PAINT MONO (-7554 5625);
FORCEPROP 1 LAST OFFPAGE TRUE
J 0
(-6950 5500);
DISPLAY 0.872340 (-6950 5500);
PAINT GREEN (-6950 5500);
DISPLAY INVISIBLE (-6950 5500);
FORCEPROP 1 LAST COMMENT_BODY TRUE
J 0
(-7175 5550);
DISPLAY 0.872340 (-7175 5550);
PAINT GREEN (-7175 5550);
DISPLAY INVISIBLE (-7175 5550);
FORCEPROP 2 LAST CDS_LIB standard
J 0
(-7275 5625);
DISPLAY INVISIBLE (-7275 5625);
FORCEPROP 2 LAST PATH I772
J 0
(-7225 5700);
DISPLAY 0.680851 (-7225 5700);
DISPLAY INVISIBLE (-7225 5700);
FORCEADD OFFPAGE..6
(-7275 5475);
FORCEPROP 2 LAST $XR1 149 
J 0
(-7674 5475);
DISPLAY 0.638298 (-7674 5475);
PAINT MONO (-7674 5475);
FORCEPROP 2 LAST $XR0 27 
J 0
(-7554 5475);
DISPLAY 0.638298 (-7554 5475);
PAINT MONO (-7554 5475);
FORCEPROP 2 LAST CDS_LIB standard
J 0
(-7275 5475);
DISPLAY INVISIBLE (-7275 5475);
FORCEPROP 1 LAST OFFPAGE TRUE
J 0
(-6950 5350);
DISPLAY 0.872340 (-6950 5350);
PAINT GREEN (-6950 5350);
DISPLAY INVISIBLE (-6950 5350);
FORCEPROP 1 LAST COMMENT_BODY TRUE
J 0
(-7175 5400);
DISPLAY 0.872340 (-7175 5400);
PAINT GREEN (-7175 5400);
DISPLAY INVISIBLE (-7175 5400);
FORCEPROP 2 LAST PATH I773
J 0
(-7225 5550);
DISPLAY 0.680851 (-7225 5550);
DISPLAY INVISIBLE (-7225 5550);
FORCEADD OFFPAGE..6
(-7275 5525);
FORCEPROP 2 LAST $XR0 55 
J 0
(-7554 5525);
DISPLAY 0.638298 (-7554 5525);
PAINT MONO (-7554 5525);
FORCEPROP 1 LAST OFFPAGE TRUE
J 0
(-6950 5400);
DISPLAY 0.872340 (-6950 5400);
PAINT GREEN (-6950 5400);
DISPLAY INVISIBLE (-6950 5400);
FORCEPROP 1 LAST COMMENT_BODY TRUE
J 0
(-7175 5450);
DISPLAY 0.872340 (-7175 5450);
PAINT GREEN (-7175 5450);
DISPLAY INVISIBLE (-7175 5450);
FORCEPROP 2 LAST CDS_LIB standard
J 0
(-7275 5525);
DISPLAY INVISIBLE (-7275 5525);
FORCEPROP 2 LAST PATH I774
J 0
(-7225 5600);
DISPLAY 0.680851 (-7225 5600);
DISPLAY INVISIBLE (-7225 5600);
FORCEADD OFFPAGE..6
(-7275 5425);
FORCEPROP 2 LAST $XR0 55 
J 0
(-7554 5425);
DISPLAY 0.638298 (-7554 5425);
PAINT MONO (-7554 5425);
FORCEPROP 2 LAST CDS_LIB standard
J 0
(-7275 5425);
DISPLAY INVISIBLE (-7275 5425);
FORCEPROP 1 LAST OFFPAGE TRUE
J 0
(-6950 5300);
DISPLAY 0.872340 (-6950 5300);
PAINT GREEN (-6950 5300);
DISPLAY INVISIBLE (-6950 5300);
FORCEPROP 1 LAST COMMENT_BODY TRUE
J 0
(-7175 5350);
DISPLAY 0.872340 (-7175 5350);
PAINT GREEN (-7175 5350);
DISPLAY INVISIBLE (-7175 5350);
FORCEPROP 2 LAST PATH I775
J 0
(-7225 5500);
DISPLAY 0.680851 (-7225 5500);
DISPLAY INVISIBLE (-7225 5500);
FORCEADD OFFPAGE..1
(-7275 5325);
FORCEPROP 2 LAST $XR0 169 
J 0
(-7587 5325);
DISPLAY 0.638298 (-7587 5325);
PAINT MONO (-7587 5325);
FORCEPROP 1 LAST OFFPAGE TRUE
J 0
(-6950 5200);
DISPLAY 0.872340 (-6950 5200);
PAINT GREEN (-6950 5200);
DISPLAY INVISIBLE (-6950 5200);
FORCEPROP 1 LAST COMMENT_BODY TRUE
J 0
(-7150 5225);
DISPLAY 0.872340 (-7150 5225);
PAINT GREEN (-7150 5225);
DISPLAY INVISIBLE (-7150 5225);
FORCEPROP 2 LAST CDS_LIB standard
J 0
(-7275 5325);
DISPLAY INVISIBLE (-7275 5325);
FORCEPROP 2 LAST PATH I776
J 0
(-7225 5400);
DISPLAY 0.680851 (-7225 5400);
DISPLAY INVISIBLE (-7225 5400);
FORCEADD OFFPAGE..6
(-7275 5375);
FORCEPROP 2 LAST $XR0 55 
J 0
(-7554 5375);
DISPLAY 0.638298 (-7554 5375);
PAINT MONO (-7554 5375);
FORCEPROP 1 LAST OFFPAGE TRUE
J 0
(-6950 5250);
DISPLAY 0.872340 (-6950 5250);
PAINT GREEN (-6950 5250);
DISPLAY INVISIBLE (-6950 5250);
FORCEPROP 1 LAST COMMENT_BODY TRUE
J 0
(-7175 5300);
DISPLAY 0.872340 (-7175 5300);
PAINT GREEN (-7175 5300);
DISPLAY INVISIBLE (-7175 5300);
FORCEPROP 2 LAST CDS_LIB standard
J 0
(-7275 5375);
DISPLAY INVISIBLE (-7275 5375);
FORCEPROP 2 LAST PATH I777
J 0
(-7225 5450);
DISPLAY 0.680851 (-7225 5450);
DISPLAY INVISIBLE (-7225 5450);
FORCEADD OFFPAGE..1
(-7275 5275);
FORCEPROP 2 LAST $XR0 176 
J 0
(-7527 5275);
DISPLAY 0.638298 (-7527 5275);
PAINT MONO (-7527 5275);
FORCEPROP 1 LAST OFFPAGE TRUE
J 0
(-6950 5150);
DISPLAY 0.872340 (-6950 5150);
PAINT GREEN (-6950 5150);
DISPLAY INVISIBLE (-6950 5150);
FORCEPROP 1 LAST COMMENT_BODY TRUE
J 0
(-7150 5175);
DISPLAY 0.872340 (-7150 5175);
PAINT GREEN (-7150 5175);
DISPLAY INVISIBLE (-7150 5175);
FORCEPROP 2 LAST CDS_LIB standard
J 0
(-7275 5275);
DISPLAY INVISIBLE (-7275 5275);
FORCEPROP 2 LAST PATH I778
J 0
(-7225 5350);
DISPLAY 0.680851 (-7225 5350);
DISPLAY INVISIBLE (-7225 5350);
FORCEADD OFFPAGE..1
(-7275 5225);
FORCEPROP 2 LAST $XR0 193 
J 0
(-7527 5225);
DISPLAY 0.638298 (-7527 5225);
PAINT MONO (-7527 5225);
FORCEPROP 1 LAST OFFPAGE TRUE
J 0
(-6950 5100);
DISPLAY 0.872340 (-6950 5100);
PAINT GREEN (-6950 5100);
DISPLAY INVISIBLE (-6950 5100);
FORCEPROP 1 LAST COMMENT_BODY TRUE
J 0
(-7150 5125);
DISPLAY 0.872340 (-7150 5125);
PAINT GREEN (-7150 5125);
DISPLAY INVISIBLE (-7150 5125);
FORCEPROP 2 LAST CDS_LIB standard
J 0
(-7275 5225);
DISPLAY INVISIBLE (-7275 5225);
FORCEPROP 2 LAST PATH I779
J 0
(-7225 5300);
DISPLAY 0.680851 (-7225 5300);
DISPLAY INVISIBLE (-7225 5300);
FORCEADD OFFPAGE..1
(-7275 5125);
FORCEPROP 2 LAST $XR5 108 
J 0
(-8127 5125);
DISPLAY 0.638298 (-8127 5125);
PAINT MONO (-8127 5125);
FORCEPROP 2 LAST $XR4 107 
J 0
(-8007 5125);
DISPLAY 0.638298 (-8007 5125);
PAINT MONO (-8007 5125);
FORCEPROP 2 LAST $XR3 106 
J 0
(-7887 5125);
DISPLAY 0.638298 (-7887 5125);
PAINT MONO (-7887 5125);
FORCEPROP 2 LAST $XR2 105 
J 0
(-7767 5125);
DISPLAY 0.638298 (-7767 5125);
PAINT MONO (-7767 5125);
FORCEPROP 2 LAST $XR1 104 
J 0
(-7647 5125);
DISPLAY 0.638298 (-7647 5125);
PAINT MONO (-7647 5125);
FORCEPROP 2 LAST $XR0 103 
J 0
(-7527 5125);
DISPLAY 0.638298 (-7527 5125);
PAINT MONO (-7527 5125);
FORCEPROP 2 LAST CDS_LIB standard
J 0
(-7275 5125);
DISPLAY INVISIBLE (-7275 5125);
FORCEPROP 1 LAST OFFPAGE TRUE
J 0
(-6950 5000);
DISPLAY 0.872340 (-6950 5000);
PAINT GREEN (-6950 5000);
DISPLAY INVISIBLE (-6950 5000);
FORCEPROP 1 LAST COMMENT_BODY TRUE
J 0
(-7150 5025);
DISPLAY 0.872340 (-7150 5025);
PAINT GREEN (-7150 5025);
DISPLAY INVISIBLE (-7150 5025);
FORCEPROP 2 LAST PATH I780
J 0
(-7225 5200);
DISPLAY 0.680851 (-7225 5200);
DISPLAY INVISIBLE (-7225 5200);
FORCEADD OFFPAGE..1
(-7275 5025);
FORCEPROP 2 LAST $XR0 54 
J 0
(-7496 5025);
DISPLAY 0.638298 (-7496 5025);
PAINT MONO (-7496 5025);
FORCEPROP 2 LAST CDS_LIB standard
J 0
(-7275 5025);
DISPLAY INVISIBLE (-7275 5025);
FORCEPROP 2 LAST PATH I782
J 0
(-7225 5100);
DISPLAY 0.680851 (-7225 5100);
DISPLAY INVISIBLE (-7225 5100);
FORCEPROP 1 LAST COMMENT_BODY TRUE
J 0
(-7150 4925);
DISPLAY 0.872340 (-7150 4925);
PAINT GREEN (-7150 4925);
DISPLAY INVISIBLE (-7150 4925);
FORCEPROP 1 LAST OFFPAGE TRUE
J 0
(-6950 4900);
DISPLAY 0.872340 (-6950 4900);
PAINT GREEN (-6950 4900);
DISPLAY INVISIBLE (-6950 4900);
FORCEADD OFFPAGE..1
(-7275 4975);
FORCEPROP 2 LAST $XR0 54 
J 0
(-7496 4975);
DISPLAY 0.638298 (-7496 4975);
PAINT MONO (-7496 4975);
FORCEPROP 2 LAST CDS_LIB standard
J 0
(-7275 4975);
DISPLAY INVISIBLE (-7275 4975);
FORCEPROP 1 LAST OFFPAGE TRUE
J 0
(-6950 4850);
DISPLAY 0.872340 (-6950 4850);
PAINT GREEN (-6950 4850);
DISPLAY INVISIBLE (-6950 4850);
FORCEPROP 1 LAST COMMENT_BODY TRUE
J 0
(-7150 4875);
DISPLAY 0.872340 (-7150 4875);
PAINT GREEN (-7150 4875);
DISPLAY INVISIBLE (-7150 4875);
FORCEPROP 2 LAST PATH I783
J 0
(-7225 5050);
DISPLAY 0.680851 (-7225 5050);
DISPLAY INVISIBLE (-7225 5050);
FORCEADD Q_RES..1
(-6425 4825);
FORCEPROP 1 LAST LOCATION R222
J 0
(-6300 4825);
DISPLAY 0.489362 (-6300 4825);
PAINT SKYBLUE (-6300 4825);
FORCEPROP 0 LAST $SEC 1
J 0
(-6300 4875);
DISPLAY 0.680851 (-6300 4875);
PAINT MONO (-6300 4875);
DISPLAY INVISIBLE (-6300 4875);
FORCEPROP 0 LAST CDS_SEC 1
J 0
(-6300 4875);
DISPLAY 1.021277 (-6300 4875);
DISPLAY INVISIBLE (-6300 4875);
FORCEPROP 1 LASTPIN (-6525 4825) $PN 1
J 0
(-6513 4837);
DISPLAY 0.489362 (-6513 4837);
PAINT MONO (-6513 4837);
FORCEPROP 1 LASTPIN (-6325 4825) $PN 2
J 0
(-6363 4837);
DISPLAY 0.489362 (-6363 4837);
PAINT MONO (-6363 4837);
FORCEPROP 1 LAST VALUE 0
J 2
(-6550 4825);
DISPLAY 0.489362 (-6550 4825);
PAINT SKYBLUE (-6550 4825);
FORCEPROP 2 LAST ROOM RST_CPU0_PLD_TO_DIMM
J 2
(-6400 4925);
DISPLAY 0.744681 (-6400 4925);
PAINT RED (-6400 4925);
DISPLAY INVISIBLE (-6400 4925);
FORCEPROP 1 LAST PACK_TYPE 0402LF
J 2
(-6250 4750);
DISPLAY 0.489362 (-6250 4750);
PAINT SKYBLUE (-6250 4750);
DISPLAY INVISIBLE (-6250 4750);
FORCEPROP 1 LAST PART_NUMBER CS00002JB38
J 2
(-6325 4875);
DISPLAY 0.489362 (-6325 4875);
PAINT SKYBLUE (-6325 4875);
DISPLAY INVISIBLE (-6325 4875);
FORCEPROP 1 LAST TOLERANCE 5%
J 0
(-6550 4800);
DISPLAY 0.489362 (-6550 4800);
PAINT SKYBLUE (-6550 4800);
DISPLAY INVISIBLE (-6550 4800);
FORCEPROP 1 LAST MATERIAL CHIP
J 2
(-6250 4800);
DISPLAY 0.489362 (-6250 4800);
PAINT SKYBLUE (-6250 4800);
DISPLAY INVISIBLE (-6250 4800);
FORCEPROP 1 LAST WATTAGE 1/16W
J 2
(-6500 4750);
DISPLAY 0.489362 (-6500 4750);
PAINT SKYBLUE (-6500 4750);
DISPLAY INVISIBLE (-6500 4750);
FORCEPROP 1 LAST PATH I784
J 0
(-6475 4975);
DISPLAY 0.978723 (-6475 4975);
PAINT WHITE (-6475 4975);
DISPLAY INVISIBLE (-6475 4975);
FORCEPROP 2 LAST CDS_LIB pure_quanta
J 2
(-6425 4825);
DISPLAY INVISIBLE (-6425 4825);
FORCEPROP 2 LAST BOM_COST MEM
J 2
(-6400 4975);
DISPLAY 0.744681 (-6400 4975);
PAINT WHITE (-6400 4975);
DISPLAY INVISIBLE (-6400 4975);
FORCEADD Q_RES..1
(-6425 4775);
FORCEPROP 1 LAST LOCATION R264
J 0
(-6300 4775);
DISPLAY 0.489362 (-6300 4775);
PAINT SKYBLUE (-6300 4775);
FORCEPROP 0 LAST $SEC 1
J 2
(-6300 4825);
DISPLAY 0.680851 (-6300 4825);
PAINT MONO (-6300 4825);
DISPLAY INVISIBLE (-6300 4825);
FORCEPROP 0 LAST CDS_SEC 1
J 2
(-6300 4825);
DISPLAY 1.021277 (-6300 4825);
DISPLAY INVISIBLE (-6300 4825);
FORCEPROP 1 LASTPIN (-6525 4775) $PN 1
J 0
(-6513 4787);
DISPLAY 0.489362 (-6513 4787);
PAINT MONO (-6513 4787);
FORCEPROP 1 LASTPIN (-6325 4775) $PN 2
J 0
(-6363 4787);
DISPLAY 0.489362 (-6363 4787);
PAINT MONO (-6363 4787);
FORCEPROP 1 LAST VALUE 0
J 2
(-6550 4775);
DISPLAY 0.489362 (-6550 4775);
PAINT SKYBLUE (-6550 4775);
FORCEPROP 2 LAST ROOM RST_CPU0_PLD_TO_DIMM
J 2
(-6400 4875);
DISPLAY 0.744681 (-6400 4875);
PAINT RED (-6400 4875);
DISPLAY INVISIBLE (-6400 4875);
FORCEPROP 1 LAST PACK_TYPE 0402LF
J 2
(-6250 4700);
DISPLAY 0.489362 (-6250 4700);
PAINT SKYBLUE (-6250 4700);
DISPLAY INVISIBLE (-6250 4700);
FORCEPROP 1 LAST PART_NUMBER CS00002JB38
J 2
(-6325 4825);
DISPLAY 0.489362 (-6325 4825);
PAINT SKYBLUE (-6325 4825);
DISPLAY INVISIBLE (-6325 4825);
FORCEPROP 1 LAST TOLERANCE 5%
J 0
(-6550 4750);
DISPLAY 0.489362 (-6550 4750);
PAINT SKYBLUE (-6550 4750);
DISPLAY INVISIBLE (-6550 4750);
FORCEPROP 1 LAST MATERIAL CHIP
J 2
(-6250 4750);
DISPLAY 0.489362 (-6250 4750);
PAINT SKYBLUE (-6250 4750);
DISPLAY INVISIBLE (-6250 4750);
FORCEPROP 1 LAST WATTAGE 1/16W
J 2
(-6500 4700);
DISPLAY 0.489362 (-6500 4700);
PAINT SKYBLUE (-6500 4700);
DISPLAY INVISIBLE (-6500 4700);
FORCEPROP 1 LAST PATH I785
J 0
(-6475 4925);
DISPLAY 0.978723 (-6475 4925);
PAINT WHITE (-6475 4925);
DISPLAY INVISIBLE (-6475 4925);
FORCEPROP 2 LAST BOM_COST MEM
J 2
(-6400 4925);
DISPLAY 0.744681 (-6400 4925);
PAINT WHITE (-6400 4925);
DISPLAY INVISIBLE (-6400 4925);
FORCEPROP 2 LAST CDS_LIB pure_quanta
J 2
(-6425 4775);
DISPLAY INVISIBLE (-6425 4775);
FORCEADD Q_RES..1
(-6425 4725);
FORCEPROP 1 LAST LOCATION R232
J 0
(-6300 4725);
DISPLAY 0.489362 (-6300 4725);
PAINT SKYBLUE (-6300 4725);
FORCEPROP 0 LAST $SEC 1
J 2
(-6300 4775);
DISPLAY 0.680851 (-6300 4775);
PAINT MONO (-6300 4775);
DISPLAY INVISIBLE (-6300 4775);
FORCEPROP 0 LAST CDS_SEC 1
J 2
(-6300 4775);
DISPLAY 1.021277 (-6300 4775);
DISPLAY INVISIBLE (-6300 4775);
FORCEPROP 1 LASTPIN (-6525 4725) $PN 1
J 0
(-6513 4737);
DISPLAY 0.489362 (-6513 4737);
PAINT MONO (-6513 4737);
FORCEPROP 1 LASTPIN (-6325 4725) $PN 2
J 0
(-6363 4737);
DISPLAY 0.489362 (-6363 4737);
PAINT MONO (-6363 4737);
FORCEPROP 1 LAST VALUE 33
J 2
(-6550 4725);
DISPLAY 0.489362 (-6550 4725);
PAINT SKYBLUE (-6550 4725);
FORCEPROP 2 LAST ROOM RST_CPU0_PLD_TO_DIMM
J 2
(-6400 4825);
DISPLAY 0.744681 (-6400 4825);
PAINT RED (-6400 4825);
DISPLAY INVISIBLE (-6400 4825);
FORCEPROP 1 LAST PACK_TYPE 0402LF
J 2
(-6250 4650);
DISPLAY 0.489362 (-6250 4650);
PAINT SKYBLUE (-6250 4650);
DISPLAY INVISIBLE (-6250 4650);
FORCEPROP 1 LAST PART_NUMBER CS03302JB29
J 2
(-6325 4775);
DISPLAY 0.489362 (-6325 4775);
PAINT SKYBLUE (-6325 4775);
DISPLAY INVISIBLE (-6325 4775);
FORCEPROP 1 LAST TOLERANCE 5%
J 0
(-6550 4700);
DISPLAY 0.489362 (-6550 4700);
PAINT SKYBLUE (-6550 4700);
DISPLAY INVISIBLE (-6550 4700);
FORCEPROP 1 LAST MATERIAL CHIP
J 2
(-6250 4700);
DISPLAY 0.489362 (-6250 4700);
PAINT SKYBLUE (-6250 4700);
DISPLAY INVISIBLE (-6250 4700);
FORCEPROP 1 LAST WATTAGE 1/16W
J 2
(-6500 4650);
DISPLAY 0.489362 (-6500 4650);
PAINT SKYBLUE (-6500 4650);
DISPLAY INVISIBLE (-6500 4650);
FORCEPROP 1 LAST PATH I786
J 0
(-6475 4875);
DISPLAY 0.978723 (-6475 4875);
PAINT WHITE (-6475 4875);
DISPLAY INVISIBLE (-6475 4875);
FORCEPROP 2 LAST BOM_COST MEM
J 2
(-6400 4875);
DISPLAY 0.744681 (-6400 4875);
PAINT WHITE (-6400 4875);
DISPLAY INVISIBLE (-6400 4875);
FORCEPROP 2 LAST CDS_LIB pure_quanta
J 2
(-6425 4725);
DISPLAY INVISIBLE (-6425 4725);
FORCEADD Q_RES..1
(-6425 4625);
FORCEPROP 1 LAST LOCATION R261
J 0
(-6300 4625);
DISPLAY 0.489362 (-6300 4625);
PAINT SKYBLUE (-6300 4625);
FORCEPROP 0 LAST $SEC 1
J 2
(-6300 4675);
DISPLAY 0.680851 (-6300 4675);
PAINT MONO (-6300 4675);
DISPLAY INVISIBLE (-6300 4675);
FORCEPROP 0 LAST CDS_SEC 1
J 2
(-6300 4675);
DISPLAY 1.021277 (-6300 4675);
DISPLAY INVISIBLE (-6300 4675);
FORCEPROP 1 LASTPIN (-6525 4625) $PN 1
J 0
(-6513 4637);
DISPLAY 0.489362 (-6513 4637);
PAINT MONO (-6513 4637);
FORCEPROP 1 LASTPIN (-6325 4625) $PN 2
J 0
(-6363 4637);
DISPLAY 0.489362 (-6363 4637);
PAINT MONO (-6363 4637);
FORCEPROP 1 LAST VALUE 0
J 2
(-6550 4625);
DISPLAY 0.489362 (-6550 4625);
PAINT SKYBLUE (-6550 4625);
FORCEPROP 2 LAST ROOM RST_CPU0_PLD_TO_DIMM
J 2
(-6400 4725);
DISPLAY 0.744681 (-6400 4725);
PAINT RED (-6400 4725);
DISPLAY INVISIBLE (-6400 4725);
FORCEPROP 1 LAST PACK_TYPE 0402LF
J 2
(-6250 4550);
DISPLAY 0.489362 (-6250 4550);
PAINT SKYBLUE (-6250 4550);
DISPLAY INVISIBLE (-6250 4550);
FORCEPROP 1 LAST PART_NUMBER CS00002JB38
J 2
(-6325 4675);
DISPLAY 0.489362 (-6325 4675);
PAINT SKYBLUE (-6325 4675);
DISPLAY INVISIBLE (-6325 4675);
FORCEPROP 1 LAST TOLERANCE 5%
J 0
(-6550 4600);
DISPLAY 0.489362 (-6550 4600);
PAINT SKYBLUE (-6550 4600);
DISPLAY INVISIBLE (-6550 4600);
FORCEPROP 1 LAST MATERIAL CHIP
J 2
(-6250 4600);
DISPLAY 0.489362 (-6250 4600);
PAINT SKYBLUE (-6250 4600);
DISPLAY INVISIBLE (-6250 4600);
FORCEPROP 1 LAST WATTAGE 1/16W
J 2
(-6500 4550);
DISPLAY 0.489362 (-6500 4550);
PAINT SKYBLUE (-6500 4550);
DISPLAY INVISIBLE (-6500 4550);
FORCEPROP 1 LAST PATH I788
J 0
(-6475 4775);
DISPLAY 0.978723 (-6475 4775);
PAINT WHITE (-6475 4775);
DISPLAY INVISIBLE (-6475 4775);
FORCEPROP 2 LAST BOM_COST MEM
J 2
(-6400 4775);
DISPLAY 0.744681 (-6400 4775);
PAINT WHITE (-6400 4775);
DISPLAY INVISIBLE (-6400 4775);
FORCEPROP 2 LAST CDS_LIB pure_quanta
J 2
(-6425 4625);
DISPLAY INVISIBLE (-6425 4625);
FORCEADD Q_RES..1
(-6425 4575);
FORCEPROP 1 LAST LOCATION R260
J 0
(-6300 4575);
DISPLAY 0.489362 (-6300 4575);
PAINT SKYBLUE (-6300 4575);
FORCEPROP 0 LAST $SEC 1
J 2
(-6300 4625);
DISPLAY 0.680851 (-6300 4625);
PAINT MONO (-6300 4625);
DISPLAY INVISIBLE (-6300 4625);
FORCEPROP 0 LAST CDS_SEC 1
J 2
(-6300 4625);
DISPLAY 1.021277 (-6300 4625);
DISPLAY INVISIBLE (-6300 4625);
FORCEPROP 1 LASTPIN (-6525 4575) $PN 1
J 0
(-6513 4587);
DISPLAY 0.489362 (-6513 4587);
PAINT MONO (-6513 4587);
FORCEPROP 1 LASTPIN (-6325 4575) $PN 2
J 0
(-6363 4587);
DISPLAY 0.489362 (-6363 4587);
PAINT MONO (-6363 4587);
FORCEPROP 1 LAST VALUE 0
J 2
(-6550 4575);
DISPLAY 0.489362 (-6550 4575);
PAINT SKYBLUE (-6550 4575);
FORCEPROP 2 LAST ROOM RST_CPU0_PLD_TO_DIMM
J 2
(-6400 4675);
DISPLAY 0.744681 (-6400 4675);
PAINT RED (-6400 4675);
DISPLAY INVISIBLE (-6400 4675);
FORCEPROP 1 LAST PACK_TYPE 0402LF
J 2
(-6250 4500);
DISPLAY 0.489362 (-6250 4500);
PAINT SKYBLUE (-6250 4500);
DISPLAY INVISIBLE (-6250 4500);
FORCEPROP 1 LAST PART_NUMBER CS00002JB38
J 2
(-6325 4625);
DISPLAY 0.489362 (-6325 4625);
PAINT SKYBLUE (-6325 4625);
DISPLAY INVISIBLE (-6325 4625);
FORCEPROP 1 LAST TOLERANCE 5%
J 0
(-6550 4550);
DISPLAY 0.489362 (-6550 4550);
PAINT SKYBLUE (-6550 4550);
DISPLAY INVISIBLE (-6550 4550);
FORCEPROP 1 LAST MATERIAL CHIP
J 2
(-6250 4550);
DISPLAY 0.489362 (-6250 4550);
PAINT SKYBLUE (-6250 4550);
DISPLAY INVISIBLE (-6250 4550);
FORCEPROP 1 LAST WATTAGE 1/16W
J 2
(-6500 4500);
DISPLAY 0.489362 (-6500 4500);
PAINT SKYBLUE (-6500 4500);
DISPLAY INVISIBLE (-6500 4500);
FORCEPROP 1 LAST PATH I789
J 0
(-6475 4725);
DISPLAY 0.978723 (-6475 4725);
PAINT WHITE (-6475 4725);
DISPLAY INVISIBLE (-6475 4725);
FORCEPROP 2 LAST BOM_COST MEM
J 2
(-6400 4725);
DISPLAY 0.744681 (-6400 4725);
PAINT WHITE (-6400 4725);
DISPLAY INVISIBLE (-6400 4725);
FORCEPROP 2 LAST CDS_LIB pure_quanta
J 2
(-6425 4575);
DISPLAY INVISIBLE (-6425 4575);
FORCEADD Q_RES..1
(-6425 4425);
FORCEPROP 1 LAST LOCATION R263
J 0
(-6300 4425);
DISPLAY 0.489362 (-6300 4425);
PAINT SKYBLUE (-6300 4425);
FORCEPROP 0 LAST $SEC 1
J 2
(-6300 4475);
DISPLAY 0.680851 (-6300 4475);
PAINT MONO (-6300 4475);
DISPLAY INVISIBLE (-6300 4475);
FORCEPROP 0 LAST CDS_SEC 1
J 2
(-6300 4475);
DISPLAY 1.021277 (-6300 4475);
DISPLAY INVISIBLE (-6300 4475);
FORCEPROP 1 LASTPIN (-6525 4425) $PN 1
J 0
(-6513 4437);
DISPLAY 0.489362 (-6513 4437);
PAINT MONO (-6513 4437);
FORCEPROP 1 LASTPIN (-6325 4425) $PN 2
J 0
(-6363 4437);
DISPLAY 0.489362 (-6363 4437);
PAINT MONO (-6363 4437);
FORCEPROP 1 LAST VALUE 0
J 2
(-6550 4425);
DISPLAY 0.489362 (-6550 4425);
PAINT SKYBLUE (-6550 4425);
FORCEPROP 2 LAST ROOM RST_CPU0_PLD_TO_DIMM
J 2
(-6400 4525);
DISPLAY 0.744681 (-6400 4525);
PAINT RED (-6400 4525);
DISPLAY INVISIBLE (-6400 4525);
FORCEPROP 1 LAST PACK_TYPE 0402LF
J 2
(-6250 4350);
DISPLAY 0.489362 (-6250 4350);
PAINT SKYBLUE (-6250 4350);
DISPLAY INVISIBLE (-6250 4350);
FORCEPROP 1 LAST PART_NUMBER CS00002JB38
J 2
(-6325 4475);
DISPLAY 0.489362 (-6325 4475);
PAINT SKYBLUE (-6325 4475);
DISPLAY INVISIBLE (-6325 4475);
FORCEPROP 1 LAST TOLERANCE 5%
J 0
(-6550 4400);
DISPLAY 0.489362 (-6550 4400);
PAINT SKYBLUE (-6550 4400);
DISPLAY INVISIBLE (-6550 4400);
FORCEPROP 1 LAST MATERIAL CHIP
J 2
(-6250 4400);
DISPLAY 0.489362 (-6250 4400);
PAINT SKYBLUE (-6250 4400);
DISPLAY INVISIBLE (-6250 4400);
FORCEPROP 1 LAST WATTAGE 1/16W
J 2
(-6500 4350);
DISPLAY 0.489362 (-6500 4350);
PAINT SKYBLUE (-6500 4350);
DISPLAY INVISIBLE (-6500 4350);
FORCEPROP 1 LAST PATH I790
J 0
(-6475 4575);
DISPLAY 0.978723 (-6475 4575);
PAINT WHITE (-6475 4575);
DISPLAY INVISIBLE (-6475 4575);
FORCEPROP 2 LAST CDS_LIB pure_quanta
J 2
(-6425 4425);
DISPLAY INVISIBLE (-6425 4425);
FORCEPROP 2 LAST BOM_COST MEM
J 2
(-6400 4575);
DISPLAY 0.744681 (-6400 4575);
PAINT WHITE (-6400 4575);
DISPLAY INVISIBLE (-6400 4575);
FORCEADD Q_RES..1
(-6425 4375);
FORCEPROP 1 LAST LOCATION R184
J 0
(-6300 4375);
DISPLAY 0.489362 (-6300 4375);
PAINT SKYBLUE (-6300 4375);
FORCEPROP 0 LAST $SEC 1
J 2
(-6300 4425);
DISPLAY 0.680851 (-6300 4425);
PAINT MONO (-6300 4425);
DISPLAY INVISIBLE (-6300 4425);
FORCEPROP 0 LAST CDS_SEC 1
J 2
(-6300 4425);
DISPLAY 1.021277 (-6300 4425);
DISPLAY INVISIBLE (-6300 4425);
FORCEPROP 1 LASTPIN (-6525 4375) $PN 1
J 0
(-6513 4387);
DISPLAY 0.489362 (-6513 4387);
PAINT MONO (-6513 4387);
FORCEPROP 1 LASTPIN (-6325 4375) $PN 2
J 0
(-6363 4387);
DISPLAY 0.489362 (-6363 4387);
PAINT MONO (-6363 4387);
FORCEPROP 1 LAST VALUE 0
J 2
(-6550 4375);
DISPLAY 0.489362 (-6550 4375);
PAINT SKYBLUE (-6550 4375);
FORCEPROP 2 LAST ROOM RST_CPU0_PLD_TO_DIMM
J 2
(-6400 4475);
DISPLAY 0.744681 (-6400 4475);
PAINT RED (-6400 4475);
DISPLAY INVISIBLE (-6400 4475);
FORCEPROP 1 LAST PACK_TYPE 0402LF
J 2
(-6250 4300);
DISPLAY 0.489362 (-6250 4300);
PAINT SKYBLUE (-6250 4300);
DISPLAY INVISIBLE (-6250 4300);
FORCEPROP 1 LAST PART_NUMBER CS00002JB38
J 2
(-6325 4425);
DISPLAY 0.489362 (-6325 4425);
PAINT SKYBLUE (-6325 4425);
DISPLAY INVISIBLE (-6325 4425);
FORCEPROP 1 LAST TOLERANCE 5%
J 0
(-6550 4350);
DISPLAY 0.489362 (-6550 4350);
PAINT SKYBLUE (-6550 4350);
DISPLAY INVISIBLE (-6550 4350);
FORCEPROP 1 LAST MATERIAL CHIP
J 2
(-6250 4350);
DISPLAY 0.489362 (-6250 4350);
PAINT SKYBLUE (-6250 4350);
DISPLAY INVISIBLE (-6250 4350);
FORCEPROP 1 LAST WATTAGE 1/16W
J 2
(-6500 4300);
DISPLAY 0.489362 (-6500 4300);
PAINT SKYBLUE (-6500 4300);
DISPLAY INVISIBLE (-6500 4300);
FORCEPROP 1 LAST PATH I791
J 0
(-6475 4525);
DISPLAY 0.978723 (-6475 4525);
PAINT WHITE (-6475 4525);
DISPLAY INVISIBLE (-6475 4525);
FORCEPROP 2 LAST BOM_COST MEM
J 2
(-6400 4525);
DISPLAY 0.744681 (-6400 4525);
PAINT WHITE (-6400 4525);
DISPLAY INVISIBLE (-6400 4525);
FORCEPROP 2 LAST CDS_LIB pure_quanta
J 2
(-6425 4375);
DISPLAY INVISIBLE (-6425 4375);
FORCEADD Q_RES..1
(-6425 4275);
FORCEPROP 1 LAST LOCATION R181
J 0
(-6300 4275);
DISPLAY 0.489362 (-6300 4275);
PAINT SKYBLUE (-6300 4275);
FORCEPROP 0 LAST $SEC 1
J 0
(-6300 4325);
DISPLAY 0.680851 (-6300 4325);
PAINT MONO (-6300 4325);
DISPLAY INVISIBLE (-6300 4325);
FORCEPROP 0 LAST CDS_SEC 1
J 0
(-6300 4325);
DISPLAY 1.021277 (-6300 4325);
DISPLAY INVISIBLE (-6300 4325);
FORCEPROP 1 LASTPIN (-6525 4275) $PN 1
J 0
(-6513 4287);
DISPLAY 0.489362 (-6513 4287);
PAINT MONO (-6513 4287);
FORCEPROP 1 LASTPIN (-6325 4275) $PN 2
J 0
(-6363 4287);
DISPLAY 0.489362 (-6363 4287);
PAINT MONO (-6363 4287);
FORCEPROP 1 LAST VALUE 0
J 2
(-6550 4275);
DISPLAY 0.489362 (-6550 4275);
PAINT SKYBLUE (-6550 4275);
FORCEPROP 2 LAST ROOM RST_CPU0_PLD_TO_DIMM
J 2
(-6400 4375);
DISPLAY 0.744681 (-6400 4375);
PAINT RED (-6400 4375);
DISPLAY INVISIBLE (-6400 4375);
FORCEPROP 1 LAST PACK_TYPE 0402LF
J 2
(-6250 4200);
DISPLAY 0.489362 (-6250 4200);
PAINT SKYBLUE (-6250 4200);
DISPLAY INVISIBLE (-6250 4200);
FORCEPROP 1 LAST PART_NUMBER CS00002JB38
J 2
(-6325 4325);
DISPLAY 0.489362 (-6325 4325);
PAINT SKYBLUE (-6325 4325);
DISPLAY INVISIBLE (-6325 4325);
FORCEPROP 1 LAST TOLERANCE 5%
J 0
(-6550 4250);
DISPLAY 0.489362 (-6550 4250);
PAINT SKYBLUE (-6550 4250);
DISPLAY INVISIBLE (-6550 4250);
FORCEPROP 1 LAST MATERIAL CHIP
J 2
(-6250 4250);
DISPLAY 0.489362 (-6250 4250);
PAINT SKYBLUE (-6250 4250);
DISPLAY INVISIBLE (-6250 4250);
FORCEPROP 1 LAST WATTAGE 1/16W
J 2
(-6500 4200);
DISPLAY 0.489362 (-6500 4200);
PAINT SKYBLUE (-6500 4200);
DISPLAY INVISIBLE (-6500 4200);
FORCEPROP 1 LAST PATH I792
J 0
(-6475 4425);
DISPLAY 0.978723 (-6475 4425);
PAINT WHITE (-6475 4425);
DISPLAY INVISIBLE (-6475 4425);
FORCEPROP 2 LAST BOM_COST MEM
J 2
(-6400 4425);
DISPLAY 0.744681 (-6400 4425);
PAINT WHITE (-6400 4425);
DISPLAY INVISIBLE (-6400 4425);
FORCEPROP 2 LAST CDS_LIB pure_quanta
J 0
(-6425 4275);
DISPLAY INVISIBLE (-6425 4275);
FORCEADD Q_RES..1
(-6425 4175);
FORCEPROP 1 LAST LOCATION R262
J 0
(-6300 4175);
DISPLAY 0.489362 (-6300 4175);
PAINT SKYBLUE (-6300 4175);
FORCEPROP 0 LAST $SEC 1
J 2
(-6300 4225);
DISPLAY 0.680851 (-6300 4225);
PAINT MONO (-6300 4225);
DISPLAY INVISIBLE (-6300 4225);
FORCEPROP 0 LAST CDS_SEC 1
J 2
(-6300 4225);
DISPLAY 1.021277 (-6300 4225);
DISPLAY INVISIBLE (-6300 4225);
FORCEPROP 1 LASTPIN (-6525 4175) $PN 1
J 0
(-6513 4187);
DISPLAY 0.489362 (-6513 4187);
PAINT MONO (-6513 4187);
FORCEPROP 1 LASTPIN (-6325 4175) $PN 2
J 0
(-6363 4187);
DISPLAY 0.489362 (-6363 4187);
PAINT MONO (-6363 4187);
FORCEPROP 1 LAST VALUE 0
J 2
(-6550 4175);
DISPLAY 0.489362 (-6550 4175);
PAINT SKYBLUE (-6550 4175);
FORCEPROP 2 LAST ROOM RST_CPU0_PLD_TO_DIMM
J 2
(-6400 4275);
DISPLAY 0.744681 (-6400 4275);
PAINT RED (-6400 4275);
DISPLAY INVISIBLE (-6400 4275);
FORCEPROP 1 LAST PACK_TYPE 0402LF
J 2
(-6250 4100);
DISPLAY 0.489362 (-6250 4100);
PAINT SKYBLUE (-6250 4100);
DISPLAY INVISIBLE (-6250 4100);
FORCEPROP 1 LAST PART_NUMBER CS00002JB38
J 2
(-6325 4225);
DISPLAY 0.489362 (-6325 4225);
PAINT SKYBLUE (-6325 4225);
DISPLAY INVISIBLE (-6325 4225);
FORCEPROP 1 LAST TOLERANCE 5%
J 0
(-6550 4150);
DISPLAY 0.489362 (-6550 4150);
PAINT SKYBLUE (-6550 4150);
DISPLAY INVISIBLE (-6550 4150);
FORCEPROP 1 LAST MATERIAL CHIP
J 2
(-6250 4150);
DISPLAY 0.489362 (-6250 4150);
PAINT SKYBLUE (-6250 4150);
DISPLAY INVISIBLE (-6250 4150);
FORCEPROP 1 LAST WATTAGE 1/16W
J 2
(-6500 4100);
DISPLAY 0.489362 (-6500 4100);
PAINT SKYBLUE (-6500 4100);
DISPLAY INVISIBLE (-6500 4100);
FORCEPROP 1 LAST PATH I793
J 0
(-6475 4325);
DISPLAY 0.978723 (-6475 4325);
PAINT WHITE (-6475 4325);
DISPLAY INVISIBLE (-6475 4325);
FORCEPROP 2 LAST BOM_COST MEM
J 2
(-6400 4325);
DISPLAY 0.744681 (-6400 4325);
PAINT WHITE (-6400 4325);
DISPLAY INVISIBLE (-6400 4325);
FORCEPROP 2 LAST CDS_LIB pure_quanta
J 2
(-6425 4175);
DISPLAY INVISIBLE (-6425 4175);
FORCEADD Q_RES..1
(-6425 4225);
FORCEPROP 1 LAST LOCATION R180
J 0
(-6300 4225);
DISPLAY 0.489362 (-6300 4225);
PAINT SKYBLUE (-6300 4225);
FORCEPROP 0 LAST $SEC 1
J 0
(-6300 4275);
DISPLAY 0.680851 (-6300 4275);
PAINT MONO (-6300 4275);
DISPLAY INVISIBLE (-6300 4275);
FORCEPROP 0 LAST CDS_SEC 1
J 0
(-6300 4275);
DISPLAY 1.021277 (-6300 4275);
DISPLAY INVISIBLE (-6300 4275);
FORCEPROP 1 LASTPIN (-6525 4225) $PN 1
J 0
(-6513 4237);
DISPLAY 0.489362 (-6513 4237);
PAINT MONO (-6513 4237);
FORCEPROP 1 LASTPIN (-6325 4225) $PN 2
J 0
(-6363 4237);
DISPLAY 0.489362 (-6363 4237);
PAINT MONO (-6363 4237);
FORCEPROP 1 LAST VALUE 0
J 2
(-6550 4225);
DISPLAY 0.489362 (-6550 4225);
PAINT SKYBLUE (-6550 4225);
FORCEPROP 2 LAST ROOM RST_CPU0_PLD_TO_DIMM
J 2
(-6400 4325);
DISPLAY 0.744681 (-6400 4325);
PAINT RED (-6400 4325);
DISPLAY INVISIBLE (-6400 4325);
FORCEPROP 1 LAST PACK_TYPE 0402LF
J 2
(-6250 4150);
DISPLAY 0.489362 (-6250 4150);
PAINT SKYBLUE (-6250 4150);
DISPLAY INVISIBLE (-6250 4150);
FORCEPROP 1 LAST PART_NUMBER CS00002JB38
J 2
(-6325 4275);
DISPLAY 0.489362 (-6325 4275);
PAINT SKYBLUE (-6325 4275);
DISPLAY INVISIBLE (-6325 4275);
FORCEPROP 1 LAST TOLERANCE 5%
J 0
(-6550 4200);
DISPLAY 0.489362 (-6550 4200);
PAINT SKYBLUE (-6550 4200);
DISPLAY INVISIBLE (-6550 4200);
FORCEPROP 1 LAST MATERIAL CHIP
J 2
(-6250 4200);
DISPLAY 0.489362 (-6250 4200);
PAINT SKYBLUE (-6250 4200);
DISPLAY INVISIBLE (-6250 4200);
FORCEPROP 1 LAST WATTAGE 1/16W
J 2
(-6500 4150);
DISPLAY 0.489362 (-6500 4150);
PAINT SKYBLUE (-6500 4150);
DISPLAY INVISIBLE (-6500 4150);
FORCEPROP 1 LAST PATH I794
J 0
(-6475 4375);
DISPLAY 0.978723 (-6475 4375);
PAINT WHITE (-6475 4375);
DISPLAY INVISIBLE (-6475 4375);
FORCEPROP 2 LAST BOM_COST MEM
J 2
(-6400 4375);
DISPLAY 0.744681 (-6400 4375);
PAINT WHITE (-6400 4375);
DISPLAY INVISIBLE (-6400 4375);
FORCEPROP 2 LAST CDS_LIB pure_quanta
J 0
(-6425 4225);
DISPLAY INVISIBLE (-6425 4225);
FORCEADD Q_RES..1
(-6425 4025);
FORCEPROP 1 LAST LOCATION R1179
J 0
(-6300 4025);
DISPLAY 0.489362 (-6300 4025);
PAINT SKYBLUE (-6300 4025);
FORCEPROP 2 LAST $SEC 1
J 2
(-6475 4225);
DISPLAY 0.680851 (-6475 4225);
PAINT MONO (-6475 4225);
DISPLAY INVISIBLE (-6475 4225);
FORCEPROP 2 LAST CDS_SEC 1
J 2
(-6475 4225);
DISPLAY 0.680851 (-6475 4225);
DISPLAY INVISIBLE (-6475 4225);
FORCEPROP 1 LASTPIN (-6525 4025) $PN 1
J 0
(-6513 4037);
DISPLAY 0.489362 (-6513 4037);
PAINT MONO (-6513 4037);
FORCEPROP 1 LASTPIN (-6325 4025) $PN 2
J 0
(-6363 4037);
DISPLAY 0.489362 (-6363 4037);
PAINT MONO (-6363 4037);
FORCEPROP 1 LAST VALUE 0
J 2
(-6550 4025);
DISPLAY 0.489362 (-6550 4025);
PAINT SKYBLUE (-6550 4025);
FORCEPROP 2 LAST ROOM RST_CPU0_PLD_TO_DIMM
J 2
(-6400 4125);
DISPLAY 0.744681 (-6400 4125);
PAINT RED (-6400 4125);
DISPLAY INVISIBLE (-6400 4125);
FORCEPROP 1 LAST PACK_TYPE 0402LF
J 2
(-6250 3950);
DISPLAY 0.489362 (-6250 3950);
PAINT SKYBLUE (-6250 3950);
DISPLAY INVISIBLE (-6250 3950);
FORCEPROP 1 LAST PART_NUMBER CS00002JB38
J 2
(-6325 4075);
DISPLAY 0.489362 (-6325 4075);
PAINT SKYBLUE (-6325 4075);
DISPLAY INVISIBLE (-6325 4075);
FORCEPROP 1 LAST TOLERANCE 5%
J 0
(-6550 4000);
DISPLAY 0.489362 (-6550 4000);
PAINT SKYBLUE (-6550 4000);
DISPLAY INVISIBLE (-6550 4000);
FORCEPROP 1 LAST MATERIAL CHIP
J 2
(-6250 4000);
DISPLAY 0.489362 (-6250 4000);
PAINT SKYBLUE (-6250 4000);
DISPLAY INVISIBLE (-6250 4000);
FORCEPROP 1 LAST WATTAGE 1/16W
J 2
(-6500 3950);
DISPLAY 0.489362 (-6500 3950);
PAINT SKYBLUE (-6500 3950);
DISPLAY INVISIBLE (-6500 3950);
FORCEPROP 1 LAST PATH I795
J 0
(-6475 4175);
DISPLAY 0.978723 (-6475 4175);
PAINT WHITE (-6475 4175);
DISPLAY INVISIBLE (-6475 4175);
FORCEPROP 2 LAST BOM_COST MEM
J 2
(-6400 4175);
DISPLAY 0.744681 (-6400 4175);
PAINT WHITE (-6400 4175);
DISPLAY INVISIBLE (-6400 4175);
FORCEPROP 2 LAST CDS_LIB pure_quanta
J 2
(-6425 4025);
DISPLAY INVISIBLE (-6425 4025);
FORCEADD OFFPAGE..1
(-7275 4925);
FORCEPROP 2 LAST $XR0 176 
J 0
(-7527 4925);
DISPLAY 0.638298 (-7527 4925);
PAINT MONO (-7527 4925);
FORCEPROP 2 LAST CDS_LIB standard
J 0
(-7275 4925);
DISPLAY INVISIBLE (-7275 4925);
FORCEPROP 1 LAST OFFPAGE TRUE
J 0
(-6950 4800);
DISPLAY 0.872340 (-6950 4800);
PAINT GREEN (-6950 4800);
DISPLAY INVISIBLE (-6950 4800);
FORCEPROP 1 LAST COMMENT_BODY TRUE
J 0
(-7150 4825);
DISPLAY 0.872340 (-7150 4825);
PAINT GREEN (-7150 4825);
DISPLAY INVISIBLE (-7150 4825);
FORCEPROP 2 LAST PATH I796
J 0
(-7225 5000);
DISPLAY 0.680851 (-7225 5000);
DISPLAY INVISIBLE (-7225 5000);
FORCEADD OFFPAGE..1
(-7275 4875);
FORCEPROP 2 LAST $XR5 102 
J 0
(-8036 4875);
DISPLAY 0.638298 (-8036 4875);
PAINT MONO (-8036 4875);
FORCEPROP 2 LAST $XR4 101 
J 0
(-7916 4875);
DISPLAY 0.638298 (-7916 4875);
PAINT MONO (-7916 4875);
FORCEPROP 2 LAST $XR3 100 
J 0
(-7796 4875);
DISPLAY 0.638298 (-7796 4875);
PAINT MONO (-7796 4875);
FORCEPROP 2 LAST $XR2 99 
J 0
(-7676 4875);
DISPLAY 0.638298 (-7676 4875);
PAINT MONO (-7676 4875);
FORCEPROP 2 LAST $XR1 98 
J 0
(-7586 4875);
DISPLAY 0.638298 (-7586 4875);
PAINT MONO (-7586 4875);
FORCEPROP 2 LAST $XR0 97 
J 0
(-7496 4875);
DISPLAY 0.638298 (-7496 4875);
PAINT MONO (-7496 4875);
FORCEPROP 2 LAST CDS_LIB standard
J 0
(-7275 4875);
DISPLAY INVISIBLE (-7275 4875);
FORCEPROP 1 LAST OFFPAGE TRUE
J 0
(-6950 4750);
DISPLAY 0.872340 (-6950 4750);
PAINT GREEN (-6950 4750);
DISPLAY INVISIBLE (-6950 4750);
FORCEPROP 1 LAST COMMENT_BODY TRUE
J 0
(-7150 4775);
DISPLAY 0.872340 (-7150 4775);
PAINT GREEN (-7150 4775);
DISPLAY INVISIBLE (-7150 4775);
FORCEPROP 2 LAST PATH I797
J 0
(-7225 4950);
DISPLAY 0.680851 (-7225 4950);
DISPLAY INVISIBLE (-7225 4950);
FORCEADD OFFPAGE..1
(-7275 4825);
FORCEPROP 2 LAST $XR0 27 
J 0
(-7496 4825);
DISPLAY 0.638298 (-7496 4825);
PAINT MONO (-7496 4825);
FORCEPROP 2 LAST CDS_LIB standard
J 0
(-7275 4825);
DISPLAY INVISIBLE (-7275 4825);
FORCEPROP 1 LAST OFFPAGE TRUE
J 0
(-6950 4700);
DISPLAY 0.872340 (-6950 4700);
PAINT GREEN (-6950 4700);
DISPLAY INVISIBLE (-6950 4700);
FORCEPROP 1 LAST COMMENT_BODY TRUE
J 0
(-7150 4725);
DISPLAY 0.872340 (-7150 4725);
PAINT GREEN (-7150 4725);
DISPLAY INVISIBLE (-7150 4725);
FORCEPROP 2 LAST PATH I798
J 0
(-7225 4900);
DISPLAY 0.680851 (-7225 4900);
DISPLAY INVISIBLE (-7225 4900);
FORCEADD OFFPAGE..1
(-7275 4775);
FORCEPROP 2 LAST $XR0 54 
J 0
(-7496 4775);
DISPLAY 0.638298 (-7496 4775);
PAINT MONO (-7496 4775);
FORCEPROP 2 LAST CDS_LIB standard
J 0
(-7275 4775);
DISPLAY INVISIBLE (-7275 4775);
FORCEPROP 1 LAST OFFPAGE TRUE
J 0
(-6950 4650);
DISPLAY 0.872340 (-6950 4650);
PAINT GREEN (-6950 4650);
DISPLAY INVISIBLE (-6950 4650);
FORCEPROP 1 LAST COMMENT_BODY TRUE
J 0
(-7150 4675);
DISPLAY 0.872340 (-7150 4675);
PAINT GREEN (-7150 4675);
DISPLAY INVISIBLE (-7150 4675);
FORCEPROP 2 LAST PATH I799
J 0
(-7225 4850);
DISPLAY 0.680851 (-7225 4850);
DISPLAY INVISIBLE (-7225 4850);
FORCEADD OFFPAGE..5
(-7275 4725);
FORCEPROP 2 LAST $XR0 176 
J 0
(-7560 4725);
DISPLAY 0.638298 (-7560 4725);
PAINT MONO (-7560 4725);
FORCEPROP 2 LAST CDS_LIB standard
J 0
(-7275 4725);
DISPLAY INVISIBLE (-7275 4725);
FORCEPROP 2 LAST PATH I801
J 0
(-7225 4800);
DISPLAY 0.680851 (-7225 4800);
DISPLAY INVISIBLE (-7225 4800);
FORCEPROP 1 LAST OFFPAGE TRUE
J 0
(-6950 4600);
DISPLAY 0.872340 (-6950 4600);
PAINT GREEN (-6950 4600);
DISPLAY INVISIBLE (-6950 4600);
FORCEPROP 1 LAST COMMENT_BODY TRUE
J 0
(-7175 4650);
DISPLAY 0.872340 (-7175 4650);
PAINT GREEN (-7175 4650);
DISPLAY INVISIBLE (-7175 4650);
FORCEADD OFFPAGE..1
(-7275 4625);
FORCEPROP 2 LAST $XR0 54 
J 0
(-7526 4625);
DISPLAY 0.638298 (-7526 4625);
PAINT MONO (-7526 4625);
FORCEPROP 2 LAST CDS_LIB standard
J 0
(-7275 4625);
DISPLAY INVISIBLE (-7275 4625);
FORCEPROP 1 LAST OFFPAGE TRUE
J 0
(-6950 4500);
DISPLAY 0.872340 (-6950 4500);
PAINT GREEN (-6950 4500);
DISPLAY INVISIBLE (-6950 4500);
FORCEPROP 1 LAST COMMENT_BODY TRUE
J 0
(-7150 4525);
DISPLAY 0.872340 (-7150 4525);
PAINT GREEN (-7150 4525);
DISPLAY INVISIBLE (-7150 4525);
FORCEPROP 2 LAST PATH I802
J 0
(-7225 4700);
DISPLAY 0.680851 (-7225 4700);
DISPLAY INVISIBLE (-7225 4700);
FORCEADD OFFPAGE..1
(-7275 4425);
FORCEPROP 2 LAST $XR0 54 
J 0
(-7496 4425);
DISPLAY 0.638298 (-7496 4425);
PAINT MONO (-7496 4425);
FORCEPROP 2 LAST CDS_LIB standard
J 0
(-7275 4425);
DISPLAY INVISIBLE (-7275 4425);
FORCEPROP 1 LAST OFFPAGE TRUE
J 0
(-6950 4300);
DISPLAY 0.872340 (-6950 4300);
PAINT GREEN (-6950 4300);
DISPLAY INVISIBLE (-6950 4300);
FORCEPROP 1 LAST COMMENT_BODY TRUE
J 0
(-7150 4325);
DISPLAY 0.872340 (-7150 4325);
PAINT GREEN (-7150 4325);
DISPLAY INVISIBLE (-7150 4325);
FORCEPROP 2 LAST PATH I803
J 0
(-7225 4500);
DISPLAY 0.680851 (-7225 4500);
DISPLAY INVISIBLE (-7225 4500);
FORCEADD OFFPAGE..1
(-7275 4475);
FORCEPROP 2 LAST $XR1 126 
J 0
(-7616 4475);
DISPLAY 0.638298 (-7616 4475);
PAINT MONO (-7616 4475);
FORCEPROP 2 LAST $XR0 82 
J 0
(-7496 4475);
DISPLAY 0.638298 (-7496 4475);
PAINT MONO (-7496 4475);
FORCEPROP 2 LAST CDS_LIB standard
J 0
(-7275 4475);
DISPLAY INVISIBLE (-7275 4475);
FORCEPROP 1 LAST OFFPAGE TRUE
J 0
(-6950 4350);
DISPLAY 0.872340 (-6950 4350);
PAINT GREEN (-6950 4350);
DISPLAY INVISIBLE (-6950 4350);
FORCEPROP 1 LAST COMMENT_BODY TRUE
J 0
(-7150 4375);
DISPLAY 0.872340 (-7150 4375);
PAINT GREEN (-7150 4375);
DISPLAY INVISIBLE (-7150 4375);
FORCEPROP 2 LAST PATH I804
J 0
(-7225 4550);
DISPLAY 0.680851 (-7225 4550);
DISPLAY INVISIBLE (-7225 4550);
FORCEADD OFFPAGE..1
(-7275 4575);
FORCEPROP 2 LAST $XR0 54 
J 0
(-7496 4575);
DISPLAY 0.638298 (-7496 4575);
PAINT MONO (-7496 4575);
FORCEPROP 2 LAST CDS_LIB standard
J 0
(-7275 4575);
DISPLAY INVISIBLE (-7275 4575);
FORCEPROP 1 LAST OFFPAGE TRUE
J 0
(-6950 4450);
DISPLAY 0.872340 (-6950 4450);
PAINT GREEN (-6950 4450);
DISPLAY INVISIBLE (-6950 4450);
FORCEPROP 1 LAST COMMENT_BODY TRUE
J 0
(-7150 4475);
DISPLAY 0.872340 (-7150 4475);
PAINT GREEN (-7150 4475);
DISPLAY INVISIBLE (-7150 4475);
FORCEPROP 2 LAST PATH I805
J 0
(-7225 4650);
DISPLAY 0.680851 (-7225 4650);
DISPLAY INVISIBLE (-7225 4650);
FORCEADD OFFPAGE..1
(-7275 4525);
FORCEPROP 2 LAST $XR1 127 
J 0
(-7616 4525);
DISPLAY 0.638298 (-7616 4525);
PAINT MONO (-7616 4525);
FORCEPROP 2 LAST $XR0 82 
J 0
(-7496 4525);
DISPLAY 0.638298 (-7496 4525);
PAINT MONO (-7496 4525);
FORCEPROP 2 LAST CDS_LIB standard
J 0
(-7275 4525);
DISPLAY INVISIBLE (-7275 4525);
FORCEPROP 1 LAST OFFPAGE TRUE
J 0
(-6950 4400);
DISPLAY 0.872340 (-6950 4400);
PAINT GREEN (-6950 4400);
DISPLAY INVISIBLE (-6950 4400);
FORCEPROP 1 LAST COMMENT_BODY TRUE
J 0
(-7150 4425);
DISPLAY 0.872340 (-7150 4425);
PAINT GREEN (-7150 4425);
DISPLAY INVISIBLE (-7150 4425);
FORCEPROP 2 LAST PATH I806
J 0
(-7225 4600);
DISPLAY 0.680851 (-7225 4600);
DISPLAY INVISIBLE (-7225 4600);
FORCEADD OFFPAGE..1
(-7275 4375);
FORCEPROP 2 LAST $XR0 27 
J 0
(-7496 4375);
DISPLAY 0.638298 (-7496 4375);
PAINT MONO (-7496 4375);
FORCEPROP 2 LAST CDS_LIB standard
J 0
(-7275 4375);
DISPLAY INVISIBLE (-7275 4375);
FORCEPROP 1 LAST OFFPAGE TRUE
J 0
(-6950 4250);
DISPLAY 0.872340 (-6950 4250);
PAINT GREEN (-6950 4250);
DISPLAY INVISIBLE (-6950 4250);
FORCEPROP 1 LAST COMMENT_BODY TRUE
J 0
(-7150 4275);
DISPLAY 0.872340 (-7150 4275);
PAINT GREEN (-7150 4275);
DISPLAY INVISIBLE (-7150 4275);
FORCEPROP 2 LAST PATH I807
J 0
(-7225 4450);
DISPLAY 0.680851 (-7225 4450);
DISPLAY INVISIBLE (-7225 4450);
FORCEADD OFFPAGE..1
(-7275 4175);
FORCEPROP 2 LAST $XR0 54 
J 0
(-7496 4175);
DISPLAY 0.638298 (-7496 4175);
PAINT MONO (-7496 4175);
FORCEPROP 2 LAST CDS_LIB standard
J 0
(-7275 4175);
DISPLAY INVISIBLE (-7275 4175);
FORCEPROP 1 LAST COMMENT_BODY TRUE
J 0
(-7150 4075);
DISPLAY 0.872340 (-7150 4075);
PAINT GREEN (-7150 4075);
DISPLAY INVISIBLE (-7150 4075);
FORCEPROP 1 LAST OFFPAGE TRUE
J 0
(-6950 4050);
DISPLAY 0.872340 (-6950 4050);
PAINT GREEN (-6950 4050);
DISPLAY INVISIBLE (-6950 4050);
FORCEPROP 2 LAST PATH I808
J 0
(-7225 4250);
DISPLAY 0.680851 (-7225 4250);
DISPLAY INVISIBLE (-7225 4250);
FORCEADD OFFPAGE..1
(-7275 4225);
FORCEPROP 2 LAST $XR0 27 
J 0
(-7496 4225);
DISPLAY 0.638298 (-7496 4225);
PAINT MONO (-7496 4225);
FORCEPROP 2 LAST CDS_LIB standard
J 0
(-7275 4225);
DISPLAY INVISIBLE (-7275 4225);
FORCEPROP 1 LAST OFFPAGE TRUE
J 0
(-6950 4100);
DISPLAY 0.872340 (-6950 4100);
PAINT GREEN (-6950 4100);
DISPLAY INVISIBLE (-6950 4100);
FORCEPROP 1 LAST COMMENT_BODY TRUE
J 0
(-7150 4125);
DISPLAY 0.872340 (-7150 4125);
PAINT GREEN (-7150 4125);
DISPLAY INVISIBLE (-7150 4125);
FORCEPROP 2 LAST PATH I809
J 0
(-7225 4300);
DISPLAY 0.680851 (-7225 4300);
DISPLAY INVISIBLE (-7225 4300);
FORCEADD OFFPAGE..1
(-7275 4275);
FORCEPROP 2 LAST $XR0 27 
J 0
(-7526 4275);
DISPLAY 0.638298 (-7526 4275);
PAINT MONO (-7526 4275);
FORCEPROP 2 LAST CDS_LIB standard
J 0
(-7275 4275);
DISPLAY INVISIBLE (-7275 4275);
FORCEPROP 1 LAST OFFPAGE TRUE
J 0
(-6950 4150);
DISPLAY 0.872340 (-6950 4150);
PAINT GREEN (-6950 4150);
DISPLAY INVISIBLE (-6950 4150);
FORCEPROP 1 LAST COMMENT_BODY TRUE
J 0
(-7150 4175);
DISPLAY 0.872340 (-7150 4175);
PAINT GREEN (-7150 4175);
DISPLAY INVISIBLE (-7150 4175);
FORCEPROP 2 LAST PATH I810
J 0
(-7225 4350);
DISPLAY 0.680851 (-7225 4350);
DISPLAY INVISIBLE (-7225 4350);
FORCEADD OFFPAGE..1
(-7275 3975);
FORCEPROP 2 LAST $XR1 34 
J 0
(-7617 3975);
DISPLAY 0.638298 (-7617 3975);
PAINT MONO (-7617 3975);
FORCEPROP 2 LAST $XR0 114 
J 0
(-7527 3975);
DISPLAY 0.638298 (-7527 3975);
PAINT MONO (-7527 3975);
FORCEPROP 1 LAST COMMENT_BODY TRUE
J 0
(-7150 3875);
DISPLAY 0.872340 (-7150 3875);
PAINT GREEN (-7150 3875);
DISPLAY INVISIBLE (-7150 3875);
FORCEPROP 1 LAST OFFPAGE TRUE
J 0
(-6950 3850);
DISPLAY 0.872340 (-6950 3850);
PAINT GREEN (-6950 3850);
DISPLAY INVISIBLE (-6950 3850);
FORCEPROP 2 LAST CDS_LIB standard
J 0
(-7275 3975);
DISPLAY INVISIBLE (-7275 3975);
FORCEPROP 2 LAST PATH I811
J 0
(-7225 4050);
DISPLAY 0.680851 (-7225 4050);
DISPLAY INVISIBLE (-7225 4050);
FORCEADD OFFPAGE..1
(-7275 4025);
FORCEPROP 2 LAST $XR1 116 
J 0
(-7616 4025);
DISPLAY 0.638298 (-7616 4025);
PAINT MONO (-7616 4025);
FORCEPROP 2 LAST $XR0 82 
J 0
(-7496 4025);
DISPLAY 0.638298 (-7496 4025);
PAINT MONO (-7496 4025);
FORCEPROP 2 LAST CDS_LIB standard
J 0
(-7275 4025);
DISPLAY INVISIBLE (-7275 4025);
FORCEPROP 1 LAST COMMENT_BODY TRUE
J 0
(-7150 3925);
DISPLAY 0.872340 (-7150 3925);
PAINT GREEN (-7150 3925);
DISPLAY INVISIBLE (-7150 3925);
FORCEPROP 1 LAST OFFPAGE TRUE
J 0
(-6950 3900);
DISPLAY 0.872340 (-6950 3900);
PAINT GREEN (-6950 3900);
DISPLAY INVISIBLE (-6950 3900);
FORCEPROP 2 LAST PATH I812
J 0
(-7225 4100);
DISPLAY 0.680851 (-7225 4100);
DISPLAY INVISIBLE (-7225 4100);
FORCEADD OFFPAGE..1
(-7275 4075);
FORCEPROP 2 LAST $XR1 183 
J 0
(-7616 4075);
DISPLAY 0.638298 (-7616 4075);
PAINT MONO (-7616 4075);
FORCEPROP 2 LAST $XR0 82 
J 0
(-7496 4075);
DISPLAY 0.638298 (-7496 4075);
PAINT MONO (-7496 4075);
FORCEPROP 2 LAST CDS_LIB standard
J 0
(-7275 4075);
DISPLAY INVISIBLE (-7275 4075);
FORCEPROP 1 LAST COMMENT_BODY TRUE
J 0
(-7150 3975);
DISPLAY 0.872340 (-7150 3975);
PAINT GREEN (-7150 3975);
DISPLAY INVISIBLE (-7150 3975);
FORCEPROP 1 LAST OFFPAGE TRUE
J 0
(-6950 3950);
DISPLAY 0.872340 (-6950 3950);
PAINT GREEN (-6950 3950);
DISPLAY INVISIBLE (-6950 3950);
FORCEPROP 2 LAST PATH I813
J 0
(-7225 4150);
DISPLAY 0.680851 (-7225 4150);
DISPLAY INVISIBLE (-7225 4150);
FORCEADD OFFPAGE..1
(-7275 3875);
FORCEPROP 2 LAST $XR1 34 
J 0
(-7617 3875);
DISPLAY 0.638298 (-7617 3875);
PAINT MONO (-7617 3875);
FORCEPROP 2 LAST $XR0 114 
J 0
(-7527 3875);
DISPLAY 0.638298 (-7527 3875);
PAINT MONO (-7527 3875);
FORCEPROP 2 LAST CDS_LIB standard
J 0
(-7275 3875);
DISPLAY INVISIBLE (-7275 3875);
FORCEPROP 1 LAST COMMENT_BODY TRUE
J 0
(-7150 3775);
DISPLAY 0.872340 (-7150 3775);
PAINT GREEN (-7150 3775);
DISPLAY INVISIBLE (-7150 3775);
FORCEPROP 1 LAST OFFPAGE TRUE
J 0
(-6950 3750);
DISPLAY 0.872340 (-6950 3750);
PAINT GREEN (-6950 3750);
DISPLAY INVISIBLE (-6950 3750);
FORCEPROP 2 LAST PATH I814
J 0
(-7225 3950);
DISPLAY 0.680851 (-7225 3950);
DISPLAY INVISIBLE (-7225 3950);
FORCEADD OFFPAGE..1
(-7275 3675);
FORCEPROP 2 LAST $XR0 158 
J 0
(-7527 3675);
DISPLAY 0.638298 (-7527 3675);
PAINT MONO (-7527 3675);
FORCEPROP 2 LAST CDS_LIB standard
J 0
(-7275 3675);
DISPLAY INVISIBLE (-7275 3675);
FORCEPROP 1 LAST COMMENT_BODY TRUE
J 0
(-7150 3575);
DISPLAY 0.872340 (-7150 3575);
PAINT GREEN (-7150 3575);
DISPLAY INVISIBLE (-7150 3575);
FORCEPROP 1 LAST OFFPAGE TRUE
J 0
(-6950 3550);
DISPLAY 0.872340 (-6950 3550);
PAINT GREEN (-6950 3550);
DISPLAY INVISIBLE (-6950 3550);
FORCEPROP 2 LAST PATH I815
J 0
(-7225 3750);
DISPLAY 0.680851 (-7225 3750);
DISPLAY INVISIBLE (-7225 3750);
FORCEADD OFFPAGE..1
(-7275 3725);
FORCEPROP 2 LAST $XR1 176 
J 0
(-7616 3725);
DISPLAY 0.638298 (-7616 3725);
PAINT MONO (-7616 3725);
FORCEPROP 2 LAST $XR0 82 
J 0
(-7496 3725);
DISPLAY 0.638298 (-7496 3725);
PAINT MONO (-7496 3725);
FORCEPROP 2 LAST CDS_LIB standard
J 0
(-7275 3725);
DISPLAY INVISIBLE (-7275 3725);
FORCEPROP 1 LAST COMMENT_BODY TRUE
J 0
(-7150 3625);
DISPLAY 0.872340 (-7150 3625);
PAINT GREEN (-7150 3625);
DISPLAY INVISIBLE (-7150 3625);
FORCEPROP 1 LAST OFFPAGE TRUE
J 0
(-6950 3600);
DISPLAY 0.872340 (-6950 3600);
PAINT GREEN (-6950 3600);
DISPLAY INVISIBLE (-6950 3600);
FORCEPROP 2 LAST PATH I816
J 0
(-7225 3800);
DISPLAY 0.680851 (-7225 3800);
DISPLAY INVISIBLE (-7225 3800);
FORCEADD OFFPAGE..1
(-7275 3775);
FORCEPROP 2 LAST $XR1 193 
J 0
(-7616 3775);
DISPLAY 0.638298 (-7616 3775);
PAINT MONO (-7616 3775);
FORCEPROP 2 LAST $XR0 82 
J 0
(-7496 3775);
DISPLAY 0.638298 (-7496 3775);
PAINT MONO (-7496 3775);
FORCEPROP 2 LAST CDS_LIB standard
J 0
(-7275 3775);
DISPLAY INVISIBLE (-7275 3775);
FORCEPROP 1 LAST COMMENT_BODY TRUE
J 0
(-7150 3675);
DISPLAY 0.872340 (-7150 3675);
PAINT GREEN (-7150 3675);
DISPLAY INVISIBLE (-7150 3675);
FORCEPROP 1 LAST OFFPAGE TRUE
J 0
(-6950 3650);
DISPLAY 0.872340 (-6950 3650);
PAINT GREEN (-6950 3650);
DISPLAY INVISIBLE (-6950 3650);
FORCEPROP 2 LAST PATH I817
J 0
(-7225 3850);
DISPLAY 0.680851 (-7225 3850);
DISPLAY INVISIBLE (-7225 3850);
FORCEADD OFFPAGE..1
(-7275 3825);
FORCEPROP 2 LAST $XR1 61 
J 0
(-7617 3825);
DISPLAY 0.638298 (-7617 3825);
PAINT MONO (-7617 3825);
FORCEPROP 2 LAST $XR0 115 
J 0
(-7527 3825);
DISPLAY 0.638298 (-7527 3825);
PAINT MONO (-7527 3825);
FORCEPROP 2 LAST CDS_LIB standard
J 0
(-7275 3825);
DISPLAY INVISIBLE (-7275 3825);
FORCEPROP 1 LAST COMMENT_BODY TRUE
J 0
(-7150 3725);
DISPLAY 0.872340 (-7150 3725);
PAINT GREEN (-7150 3725);
DISPLAY INVISIBLE (-7150 3725);
FORCEPROP 1 LAST OFFPAGE TRUE
J 0
(-6950 3700);
DISPLAY 0.872340 (-6950 3700);
PAINT GREEN (-6950 3700);
DISPLAY INVISIBLE (-6950 3700);
FORCEPROP 2 LAST PATH I818
J 0
(-7225 3900);
DISPLAY 0.680851 (-7225 3900);
DISPLAY INVISIBLE (-7225 3900);
FORCEADD OFFPAGE..1
(-7275 3625);
FORCEPROP 2 LAST $XR1 83 
J 0
(-7617 3625);
DISPLAY 0.638298 (-7617 3625);
PAINT MONO (-7617 3625);
FORCEPROP 2 LAST $XR0 117 
J 0
(-7527 3625);
DISPLAY 0.638298 (-7527 3625);
PAINT MONO (-7527 3625);
FORCEPROP 2 LAST CDS_LIB standard
J 0
(-7275 3625);
DISPLAY INVISIBLE (-7275 3625);
FORCEPROP 1 LAST COMMENT_BODY TRUE
J 0
(-7150 3525);
DISPLAY 0.872340 (-7150 3525);
PAINT GREEN (-7150 3525);
DISPLAY INVISIBLE (-7150 3525);
FORCEPROP 1 LAST OFFPAGE TRUE
J 0
(-6950 3500);
DISPLAY 0.872340 (-6950 3500);
PAINT GREEN (-6950 3500);
DISPLAY INVISIBLE (-6950 3500);
FORCEPROP 2 LAST PATH I819
J 0
(-7225 3700);
DISPLAY 0.680851 (-7225 3700);
DISPLAY INVISIBLE (-7225 3700);
FORCEADD OFFPAGE..1
(-7275 3575);
FORCEPROP 2 LAST $XR0 158 
J 0
(-7527 3575);
DISPLAY 0.638298 (-7527 3575);
PAINT MONO (-7527 3575);
FORCEPROP 2 LAST CDS_LIB standard
J 0
(-7275 3575);
DISPLAY INVISIBLE (-7275 3575);
FORCEPROP 1 LAST COMMENT_BODY TRUE
J 0
(-7150 3475);
DISPLAY 0.872340 (-7150 3475);
PAINT GREEN (-7150 3475);
DISPLAY INVISIBLE (-7150 3475);
FORCEPROP 1 LAST OFFPAGE TRUE
J 0
(-6950 3450);
DISPLAY 0.872340 (-6950 3450);
PAINT GREEN (-6950 3450);
DISPLAY INVISIBLE (-6950 3450);
FORCEPROP 2 LAST PATH I820
J 0
(-7225 3650);
DISPLAY 0.680851 (-7225 3650);
DISPLAY INVISIBLE (-7225 3650);
FORCEADD OFFPAGE..1
(-7275 3525);
FORCEPROP 2 LAST $XR0 158 
J 0
(-7527 3525);
DISPLAY 0.638298 (-7527 3525);
PAINT MONO (-7527 3525);
FORCEPROP 2 LAST CDS_LIB standard
J 0
(-7275 3525);
DISPLAY INVISIBLE (-7275 3525);
FORCEPROP 1 LAST COMMENT_BODY TRUE
J 0
(-7150 3425);
DISPLAY 0.872340 (-7150 3425);
PAINT GREEN (-7150 3425);
DISPLAY INVISIBLE (-7150 3425);
FORCEPROP 1 LAST OFFPAGE TRUE
J 0
(-6950 3400);
DISPLAY 0.872340 (-6950 3400);
PAINT GREEN (-6950 3400);
DISPLAY INVISIBLE (-6950 3400);
FORCEPROP 2 LAST PATH I821
J 0
(-7225 3600);
DISPLAY 0.680851 (-7225 3600);
DISPLAY INVISIBLE (-7225 3600);
FORCEADD OFFPAGE..2
(-2300 3675);
FORCEPROP 2 LAST $XR0 84 
J 0
(-2111 3675);
DISPLAY 0.638298 (-2111 3675);
PAINT MONO (-2111 3675);
FORCEPROP 2 LAST CDS_LIB standard
J 0
(-2300 3675);
DISPLAY INVISIBLE (-2300 3675);
FORCEPROP 2 LAST PATH I832
J 0
(-2125 3750);
DISPLAY 0.680851 (-2125 3750);
DISPLAY INVISIBLE (-2125 3750);
FORCEPROP 1 LAST OFFPAGE TRUE
J 0
(-1975 3550);
DISPLAY 0.872340 (-1975 3550);
PAINT GREEN (-1975 3550);
DISPLAY INVISIBLE (-1975 3550);
FORCEPROP 1 LAST COMMENT_BODY TRUE
J 0
(-2345 3580);
DISPLAY 0.872340 (-2345 3580);
PAINT GREEN (-2345 3580);
DISPLAY INVISIBLE (-2345 3580);
FORCEADD GND..1
(-6175 300);
FORCEPROP 3 LASTPIN (-6175 350) SIG_NAME GND\g
J 0
(-6165 360);
DISPLAY 0.659574 (-6165 360);
PAINT MONO (-6165 360);
DISPLAY INVISIBLE (-6165 360);
FORCEPROP 1 LAST HDL_POWER GND
J 0
(-6175 450);
DISPLAY 0.851064 (-6175 450);
PAINT GREEN (-6175 450);
DISPLAY INVISIBLE (-6175 450);
FORCEPROP 1 LAST PATH I833
J 0
(-6100 300);
DISPLAY 0.872340 (-6100 300);
PAINT AQUA (-6100 300);
DISPLAY INVISIBLE (-6100 300);
FORCEPROP 2 LAST CDS_LIB pure_quanta_power
J 0
(-6175 300);
DISPLAY INVISIBLE (-6175 300);
FORCEPROP 1 LAST SIZE 1B
J 0
(-6100 250);
DISPLAY 0.851064 (-6100 250);
PAINT GREEN (-6100 250);
DISPLAY INVISIBLE (-6100 250);
FORCEADD LCMXO3D9400HC5BG484C..6
(-6775 1650);
FORCEPROP 1 LAST LOCATION U18
J 0
(-7025 3125);
DISPLAY 0.489362 (-7025 3125);
PAINT SKYBLUE (-7025 3125);
FORCEPROP 0 LAST $SEC 6
J 0
(-6990 3410);
DISPLAY 0.680851 (-6990 3410);
PAINT MONO (-6990 3410);
DISPLAY INVISIBLE (-6990 3410);
FORCEPROP 0 LAST CDS_SEC 6
J 0
(-6990 3410);
DISPLAY 0.680851 (-6990 3410);
DISPLAY INVISIBLE (-6990 3410);
FORCEPROP 0 LASTPIN (-6375 2950) $PN A1
J 0
(-6365 2960);
DISPLAY 0.489362 (-6365 2960);
PAINT MONO (-6365 2960);
FORCEPROP 0 LASTPIN (-6375 2900) $PN A22
J 0
(-6365 2910);
DISPLAY 0.489362 (-6365 2910);
PAINT MONO (-6365 2910);
FORCEPROP 0 LASTPIN (-6375 450) $PN AB1
J 0
(-6365 460);
DISPLAY 0.489362 (-6365 460);
PAINT MONO (-6365 460);
FORCEPROP 0 LASTPIN (-6375 400) $PN AB22
J 0
(-6365 410);
DISPLAY 0.489362 (-6365 410);
PAINT MONO (-6365 410);
FORCEPROP 0 LASTPIN (-6375 2850) $PN B7
J 0
(-6365 2860);
DISPLAY 0.489362 (-6365 2860);
PAINT MONO (-6365 2860);
FORCEPROP 0 LASTPIN (-6375 2800) $PN B16
J 0
(-6365 2810);
DISPLAY 0.489362 (-6365 2810);
PAINT MONO (-6365 2810);
FORCEPROP 0 LASTPIN (-6375 2750) $PN C2
J 0
(-6365 2760);
DISPLAY 0.489362 (-6365 2760);
PAINT MONO (-6365 2760);
FORCEPROP 0 LASTPIN (-6375 2700) $PN C11
J 0
(-6365 2710);
DISPLAY 0.489362 (-6365 2710);
PAINT MONO (-6365 2710);
FORCEPROP 0 LASTPIN (-6375 2650) $PN E5
J 0
(-6365 2660);
DISPLAY 0.489362 (-6365 2660);
PAINT MONO (-6365 2660);
FORCEPROP 0 LASTPIN (-6375 2600) $PN E18
J 0
(-6365 2610);
DISPLAY 0.489362 (-6365 2610);
PAINT MONO (-6365 2610);
FORCEPROP 0 LASTPIN (-6375 2550) $PN F2
J 0
(-6365 2560);
DISPLAY 0.489362 (-6365 2560);
PAINT MONO (-6365 2560);
FORCEPROP 0 LASTPIN (-6375 2500) $PN F21
J 0
(-6365 2510);
DISPLAY 0.489362 (-6365 2510);
PAINT MONO (-6365 2510);
FORCEPROP 0 LASTPIN (-6375 2450) $PN H8
J 0
(-6365 2460);
DISPLAY 0.489362 (-6365 2460);
PAINT MONO (-6365 2460);
FORCEPROP 0 LASTPIN (-6375 2400) $PN H10
J 0
(-6365 2410);
DISPLAY 0.489362 (-6365 2410);
PAINT MONO (-6365 2410);
FORCEPROP 0 LASTPIN (-6375 2350) $PN H13
J 0
(-6365 2360);
DISPLAY 0.489362 (-6365 2360);
PAINT MONO (-6365 2360);
FORCEPROP 0 LASTPIN (-6375 2300) $PN H15
J 0
(-6365 2310);
DISPLAY 0.489362 (-6365 2310);
PAINT MONO (-6365 2310);
FORCEPROP 0 LASTPIN (-6375 2250) $PN J9
J 0
(-6365 2260);
DISPLAY 0.489362 (-6365 2260);
PAINT MONO (-6365 2260);
FORCEPROP 0 LASTPIN (-6375 2200) $PN J10
J 0
(-6365 2210);
DISPLAY 0.489362 (-6365 2210);
PAINT MONO (-6365 2210);
FORCEPROP 0 LASTPIN (-6375 2150) $PN J11
J 0
(-6365 2160);
DISPLAY 0.489362 (-6365 2160);
PAINT MONO (-6365 2160);
FORCEPROP 0 LASTPIN (-6375 2100) $PN J12
J 0
(-6365 2110);
DISPLAY 0.489362 (-6365 2110);
PAINT MONO (-6365 2110);
FORCEPROP 0 LASTPIN (-6375 2050) $PN J13
J 0
(-6365 2060);
DISPLAY 0.489362 (-6365 2060);
PAINT MONO (-6365 2060);
FORCEPROP 0 LASTPIN (-6375 2000) $PN J14
J 0
(-6365 2010);
DISPLAY 0.489362 (-6365 2010);
PAINT MONO (-6365 2010);
FORCEPROP 0 LASTPIN (-6375 1950) $PN K9
J 0
(-6365 1960);
DISPLAY 0.489362 (-6365 1960);
PAINT MONO (-6365 1960);
FORCEPROP 0 LASTPIN (-6375 1900) $PN K14
J 0
(-6365 1910);
DISPLAY 0.489362 (-6365 1910);
PAINT MONO (-6365 1910);
FORCEPROP 0 LASTPIN (-6375 1850) $PN K21
J 0
(-6365 1860);
DISPLAY 0.489362 (-6365 1860);
PAINT MONO (-6365 1860);
FORCEPROP 0 LASTPIN (-6375 1800) $PN L2
J 0
(-6365 1810);
DISPLAY 0.489362 (-6365 1810);
PAINT MONO (-6365 1810);
FORCEPROP 0 LASTPIN (-6375 1750) $PN L9
J 0
(-6365 1760);
DISPLAY 0.489362 (-6365 1760);
PAINT MONO (-6365 1760);
FORCEPROP 0 LASTPIN (-6375 1700) $PN L10
J 0
(-6365 1710);
DISPLAY 0.489362 (-6365 1710);
PAINT MONO (-6365 1710);
FORCEPROP 0 LASTPIN (-6375 1650) $PN L13
J 0
(-6365 1660);
DISPLAY 0.489362 (-6365 1660);
PAINT MONO (-6365 1660);
FORCEPROP 0 LASTPIN (-6375 1600) $PN L14
J 0
(-6365 1610);
DISPLAY 0.489362 (-6365 1610);
PAINT MONO (-6365 1610);
FORCEPROP 0 LASTPIN (-6375 1550) $PN L18
J 0
(-6365 1560);
DISPLAY 0.489362 (-6365 1560);
PAINT MONO (-6365 1560);
FORCEPROP 0 LASTPIN (-6375 1500) $PN M4
J 0
(-6365 1510);
DISPLAY 0.489362 (-6365 1510);
PAINT MONO (-6365 1510);
FORCEPROP 0 LASTPIN (-6375 1450) $PN M9
J 0
(-6365 1460);
DISPLAY 0.489362 (-6365 1460);
PAINT MONO (-6365 1460);
FORCEPROP 0 LASTPIN (-6375 1400) $PN M10
J 0
(-6365 1410);
DISPLAY 0.489362 (-6365 1410);
PAINT MONO (-6365 1410);
FORCEPROP 0 LASTPIN (-6375 1350) $PN M13
J 0
(-6365 1360);
DISPLAY 0.489362 (-6365 1360);
PAINT MONO (-6365 1360);
FORCEPROP 0 LASTPIN (-6375 1300) $PN M14
J 0
(-6365 1310);
DISPLAY 0.489362 (-6365 1310);
PAINT MONO (-6365 1310);
FORCEPROP 0 LASTPIN (-6375 1250) $PN N9
J 0
(-6365 1260);
DISPLAY 0.489362 (-6365 1260);
PAINT MONO (-6365 1260);
FORCEPROP 0 LASTPIN (-6375 1200) $PN N14
J 0
(-6365 1210);
DISPLAY 0.489362 (-6365 1210);
PAINT MONO (-6365 1210);
FORCEPROP 0 LASTPIN (-6375 1150) $PN N21
J 0
(-6365 1160);
DISPLAY 0.489362 (-6365 1160);
PAINT MONO (-6365 1160);
FORCEPROP 0 LASTPIN (-6375 1100) $PN P9
J 0
(-6365 1110);
DISPLAY 0.489362 (-6365 1110);
PAINT MONO (-6365 1110);
FORCEPROP 0 LASTPIN (-6375 1050) $PN P10
J 0
(-6365 1060);
DISPLAY 0.489362 (-6365 1060);
PAINT MONO (-6365 1060);
FORCEPROP 0 LASTPIN (-6375 1000) $PN P11
J 0
(-6365 1010);
DISPLAY 0.489362 (-6365 1010);
PAINT MONO (-6365 1010);
FORCEPROP 0 LASTPIN (-6375 950) $PN P12
J 0
(-6365 960);
DISPLAY 0.489362 (-6365 960);
PAINT MONO (-6365 960);
FORCEPROP 0 LASTPIN (-6375 900) $PN P13
J 0
(-6365 910);
DISPLAY 0.489362 (-6365 910);
PAINT MONO (-6365 910);
FORCEPROP 0 LASTPIN (-6375 850) $PN P14
J 0
(-6365 860);
DISPLAY 0.489362 (-6365 860);
PAINT MONO (-6365 860);
FORCEPROP 0 LASTPIN (-6375 800) $PN R8
J 0
(-6365 810);
DISPLAY 0.489362 (-6365 810);
PAINT MONO (-6365 810);
FORCEPROP 0 LASTPIN (-6375 750) $PN R15
J 0
(-6365 760);
DISPLAY 0.489362 (-6365 760);
PAINT MONO (-6365 760);
FORCEPROP 0 LASTPIN (-6375 700) $PN V2
J 0
(-6365 710);
DISPLAY 0.489362 (-6365 710);
PAINT MONO (-6365 710);
FORCEPROP 0 LASTPIN (-6375 650) $PN V21
J 0
(-6365 660);
DISPLAY 0.489362 (-6365 660);
PAINT MONO (-6365 660);
FORCEPROP 0 LASTPIN (-6375 600) $PN W12
J 0
(-6365 610);
DISPLAY 0.489362 (-6365 610);
PAINT MONO (-6365 610);
FORCEPROP 0 LASTPIN (-6375 550) $PN Y7
J 0
(-6365 560);
DISPLAY 0.489362 (-6365 560);
PAINT MONO (-6365 560);
FORCEPROP 0 LASTPIN (-6375 500) $PN Y16
J 0
(-6365 510);
DISPLAY 0.489362 (-6365 510);
PAINT MONO (-6365 510);
FORCEPROP 1 LAST PART_NUMBER AJ094000T05
J 0
(-7025 3067);
DISPLAY 0.489362 (-7025 3067);
PAINT SKYBLUE (-7025 3067);
FORCEPROP 2 LAST VALUE LCMXO3D-9400HC-5BG484C
J 0
(-7025 3180);
DISPLAY 0.489362 (-7025 3180);
PAINT SKYBLUE (-7025 3180);
FORCEPROP 1 LAST MATERIAL IC
J 0
(-7025 3015);
DISPLAY 0.489362 (-7025 3015);
PAINT SKYBLUE (-7025 3015);
FORCEPROP 2 LAST PART_TYPE SMLF
J 0
(-7025 3225);
DISPLAY 0.680851 (-7025 3225);
FORCEPROP 1 LAST PATH I834
J 0
(-6775 1650);
DISPLAY 0.723404 (-6775 1650);
PAINT GREEN (-6775 1650);
DISPLAY INVISIBLE (-6775 1650);
FORCEPROP 1 LAST NEEDS_NO_SIZE TRUE
J 0
(-6775 1650);
DISPLAY 0.723404 (-6775 1650);
PAINT GREEN (-6775 1650);
DISPLAY INVISIBLE (-6775 1650);
FORCEPROP 1 LAST CDS_LMAN_SYM_OUTLINE -250,1350,250,-1350
J 0
(-6775 1650);
DISPLAY 0.468085 (-6775 1650);
PAINT GREEN (-6775 1650);
DISPLAY INVISIBLE (-6775 1650);
FORCEPROP 2 LAST CDS_LIB pure_quanta
J 0
(-6775 1650);
DISPLAY INVISIBLE (-6775 1650);
FORCEADD OFFPAGE..2
(-2100 5525);
FORCEPROP 2 LAST $XR0 82 
J 0
(-1911 5525);
DISPLAY 0.638298 (-1911 5525);
PAINT MONO (-1911 5525);
FORCEPROP 1 LAST OFFPAGE TRUE
J 0
(-1775 5400);
DISPLAY 0.872340 (-1775 5400);
PAINT GREEN (-1775 5400);
DISPLAY INVISIBLE (-1775 5400);
FORCEPROP 1 LAST COMMENT_BODY TRUE
J 0
(-2145 5430);
DISPLAY 0.872340 (-2145 5430);
PAINT GREEN (-2145 5430);
DISPLAY INVISIBLE (-2145 5430);
FORCEPROP 2 LAST PATH I835
J 0
(-1925 5600);
DISPLAY 0.680851 (-1925 5600);
DISPLAY INVISIBLE (-1925 5600);
FORCEPROP 2 LAST CDS_LIB standard
J 0
(-2100 5525);
DISPLAY INVISIBLE (-2100 5525);
FORCEADD OFFPAGE..2
(-2100 5475);
FORCEPROP 2 LAST $XR0 82 
J 0
(-1911 5475);
DISPLAY 0.638298 (-1911 5475);
PAINT MONO (-1911 5475);
FORCEPROP 1 LAST COMMENT_BODY TRUE
J 0
(-2145 5380);
DISPLAY 0.872340 (-2145 5380);
PAINT GREEN (-2145 5380);
DISPLAY INVISIBLE (-2145 5380);
FORCEPROP 1 LAST OFFPAGE TRUE
J 0
(-1775 5350);
DISPLAY 0.872340 (-1775 5350);
PAINT GREEN (-1775 5350);
DISPLAY INVISIBLE (-1775 5350);
FORCEPROP 2 LAST PATH I836
J 0
(-1925 5550);
DISPLAY 0.680851 (-1925 5550);
DISPLAY INVISIBLE (-1925 5550);
FORCEPROP 2 LAST CDS_LIB standard
J 0
(-2100 5475);
DISPLAY INVISIBLE (-2100 5475);
FORCEADD OFFPAGE..2
(-2100 5425);
FORCEPROP 2 LAST $XR0 82 
J 0
(-1911 5425);
DISPLAY 0.638298 (-1911 5425);
PAINT MONO (-1911 5425);
FORCEPROP 1 LAST COMMENT_BODY TRUE
J 0
(-2145 5330);
DISPLAY 0.872340 (-2145 5330);
PAINT GREEN (-2145 5330);
DISPLAY INVISIBLE (-2145 5330);
FORCEPROP 1 LAST OFFPAGE TRUE
J 0
(-1775 5300);
DISPLAY 0.872340 (-1775 5300);
PAINT GREEN (-1775 5300);
DISPLAY INVISIBLE (-1775 5300);
FORCEPROP 2 LAST PATH I837
J 0
(-1925 5500);
DISPLAY 0.680851 (-1925 5500);
DISPLAY INVISIBLE (-1925 5500);
FORCEPROP 2 LAST CDS_LIB standard
J 0
(-2100 5425);
DISPLAY INVISIBLE (-2100 5425);
FORCEADD Q_RES..1
(-3225 5875);
FORCEPROP 1 LAST LOCATION R266
J 0
(-3100 5875);
DISPLAY 0.489362 (-3100 5875);
PAINT SKYBLUE (-3100 5875);
FORCEPROP 0 LAST $SEC 1
J 0
(-3100 5900);
DISPLAY 0.680851 (-3100 5900);
PAINT MONO (-3100 5900);
DISPLAY INVISIBLE (-3100 5900);
FORCEPROP 0 LAST CDS_SEC 1
J 0
(-3100 5900);
DISPLAY 0.680851 (-3100 5900);
DISPLAY INVISIBLE (-3100 5900);
FORCEPROP 1 LASTPIN (-3325 5875) $PN 1
J 0
(-3313 5887);
DISPLAY 0.510638 (-3313 5887);
PAINT MONO (-3313 5887);
FORCEPROP 1 LASTPIN (-3125 5875) $PN 2
J 0
(-3163 5887);
DISPLAY 0.510638 (-3163 5887);
PAINT MONO (-3163 5887);
FORCEPROP 1 LAST VALUE 33
J 2
(-3350 5875);
DISPLAY 0.489362 (-3350 5875);
PAINT SKYBLUE (-3350 5875);
FORCEPROP 2 LAST CDS_LIB pure_quanta
J 0
(-3225 5875);
DISPLAY INVISIBLE (-3225 5875);
FORCEPROP 1 LAST PATH I838
J 0
(-3275 6025);
DISPLAY 0.978723 (-3275 6025);
PAINT WHITE (-3275 6025);
DISPLAY INVISIBLE (-3275 6025);
FORCEPROP 2 LAST BOM_COST MEM
J 2
(-3200 6025);
DISPLAY 0.744681 (-3200 6025);
PAINT WHITE (-3200 6025);
DISPLAY INVISIBLE (-3200 6025);
FORCEPROP 1 LAST WATTAGE 1/16W
J 2
(-3300 5800);
DISPLAY 0.489362 (-3300 5800);
PAINT SKYBLUE (-3300 5800);
DISPLAY INVISIBLE (-3300 5800);
FORCEPROP 1 LAST MATERIAL CHIP
J 2
(-3050 5850);
DISPLAY 0.489362 (-3050 5850);
PAINT SKYBLUE (-3050 5850);
DISPLAY INVISIBLE (-3050 5850);
FORCEPROP 1 LAST TOLERANCE 5%
J 0
(-3350 5850);
DISPLAY 0.489362 (-3350 5850);
PAINT SKYBLUE (-3350 5850);
DISPLAY INVISIBLE (-3350 5850);
FORCEPROP 1 LAST PART_NUMBER CS03302JB29
J 2
(-3125 5925);
DISPLAY 0.489362 (-3125 5925);
PAINT SKYBLUE (-3125 5925);
DISPLAY INVISIBLE (-3125 5925);
FORCEPROP 1 LAST PACK_TYPE 0402LF
J 2
(-3050 5800);
DISPLAY 0.489362 (-3050 5800);
PAINT SKYBLUE (-3050 5800);
DISPLAY INVISIBLE (-3050 5800);
FORCEPROP 2 LAST ROOM RST_CPU0_PLD_TO_DIMM
J 2
(-3200 5975);
DISPLAY 0.744681 (-3200 5975);
PAINT RED (-3200 5975);
DISPLAY INVISIBLE (-3200 5975);
FORCEADD OFFPAGE..2
(-2125 5875);
FORCEPROP 2 LAST $XR0 54 
J 0
(-1936 5875);
DISPLAY 0.638298 (-1936 5875);
PAINT MONO (-1936 5875);
FORCEPROP 2 LAST CDS_LIB standard
J 0
(-2125 5875);
DISPLAY INVISIBLE (-2125 5875);
FORCEPROP 2 LAST PATH I839
J 0
(-1950 5950);
DISPLAY 0.680851 (-1950 5950);
DISPLAY INVISIBLE (-1950 5950);
FORCEPROP 1 LAST OFFPAGE TRUE
J 0
(-1800 5750);
DISPLAY 0.872340 (-1800 5750);
PAINT GREEN (-1800 5750);
DISPLAY INVISIBLE (-1800 5750);
FORCEPROP 1 LAST COMMENT_BODY TRUE
J 0
(-2170 5780);
DISPLAY 0.872340 (-2170 5780);
PAINT GREEN (-2170 5780);
DISPLAY INVISIBLE (-2170 5780);
FORCEADD Q_RES..1
(-3225 5775);
FORCEPROP 1 LAST LOCATION R220
J 0
(-3100 5775);
DISPLAY 0.489362 (-3100 5775);
PAINT SKYBLUE (-3100 5775);
FORCEPROP 0 LAST $SEC 1
J 0
(-3100 5800);
DISPLAY 0.680851 (-3100 5800);
PAINT MONO (-3100 5800);
DISPLAY INVISIBLE (-3100 5800);
FORCEPROP 0 LAST CDS_SEC 1
J 0
(-3100 5800);
DISPLAY 0.680851 (-3100 5800);
DISPLAY INVISIBLE (-3100 5800);
FORCEPROP 1 LASTPIN (-3325 5775) $PN 1
J 0
(-3313 5787);
DISPLAY 0.510638 (-3313 5787);
PAINT MONO (-3313 5787);
FORCEPROP 1 LASTPIN (-3125 5775) $PN 2
J 0
(-3163 5787);
DISPLAY 0.510638 (-3163 5787);
PAINT MONO (-3163 5787);
FORCEPROP 1 LAST VALUE 33
J 2
(-3350 5775);
DISPLAY 0.489362 (-3350 5775);
PAINT SKYBLUE (-3350 5775);
FORCEPROP 2 LAST CDS_LIB pure_quanta
J 0
(-3225 5775);
DISPLAY INVISIBLE (-3225 5775);
FORCEPROP 1 LAST PATH I840
J 0
(-3275 5925);
DISPLAY 0.978723 (-3275 5925);
PAINT WHITE (-3275 5925);
DISPLAY INVISIBLE (-3275 5925);
FORCEPROP 2 LAST ROOM RST_CPU0_PLD_TO_DIMM
J 2
(-3200 5875);
DISPLAY 0.744681 (-3200 5875);
PAINT RED (-3200 5875);
DISPLAY INVISIBLE (-3200 5875);
FORCEPROP 1 LAST PACK_TYPE 0402LF
J 2
(-3050 5700);
DISPLAY 0.489362 (-3050 5700);
PAINT SKYBLUE (-3050 5700);
DISPLAY INVISIBLE (-3050 5700);
FORCEPROP 1 LAST PART_NUMBER CS03302JB29
J 2
(-3125 5825);
DISPLAY 0.489362 (-3125 5825);
PAINT SKYBLUE (-3125 5825);
DISPLAY INVISIBLE (-3125 5825);
FORCEPROP 1 LAST TOLERANCE 5%
J 0
(-3350 5750);
DISPLAY 0.489362 (-3350 5750);
PAINT SKYBLUE (-3350 5750);
DISPLAY INVISIBLE (-3350 5750);
FORCEPROP 1 LAST MATERIAL CHIP
J 2
(-3050 5750);
DISPLAY 0.489362 (-3050 5750);
PAINT SKYBLUE (-3050 5750);
DISPLAY INVISIBLE (-3050 5750);
FORCEPROP 1 LAST WATTAGE 1/16W
J 2
(-3300 5700);
DISPLAY 0.489362 (-3300 5700);
PAINT SKYBLUE (-3300 5700);
DISPLAY INVISIBLE (-3300 5700);
FORCEPROP 2 LAST BOM_COST MEM
J 2
(-3200 5925);
DISPLAY 0.744681 (-3200 5925);
PAINT WHITE (-3200 5925);
DISPLAY INVISIBLE (-3200 5925);
FORCEADD OFFPAGE..2
(-2125 5775);
FORCEPROP 2 LAST $XR0 27 
J 0
(-1936 5775);
DISPLAY 0.638298 (-1936 5775);
PAINT MONO (-1936 5775);
FORCEPROP 2 LAST CDS_LIB standard
J 0
(-2125 5775);
DISPLAY INVISIBLE (-2125 5775);
FORCEPROP 2 LAST PATH I841
J 0
(-1950 5850);
DISPLAY 0.680851 (-1950 5850);
DISPLAY INVISIBLE (-1950 5850);
FORCEPROP 1 LAST OFFPAGE TRUE
J 0
(-1800 5650);
DISPLAY 0.872340 (-1800 5650);
PAINT GREEN (-1800 5650);
DISPLAY INVISIBLE (-1800 5650);
FORCEPROP 1 LAST COMMENT_BODY TRUE
J 0
(-2170 5680);
DISPLAY 0.872340 (-2170 5680);
PAINT GREEN (-2170 5680);
DISPLAY INVISIBLE (-2170 5680);
FORCEADD Q_RES..1
(-3225 5575);
FORCEPROP 1 LAST LOCATION R221
J 0
(-3100 5575);
DISPLAY 0.489362 (-3100 5575);
PAINT SKYBLUE (-3100 5575);
FORCEPROP 0 LAST $SEC 1
J 0
(-3100 5600);
DISPLAY 0.680851 (-3100 5600);
PAINT MONO (-3100 5600);
DISPLAY INVISIBLE (-3100 5600);
FORCEPROP 0 LAST CDS_SEC 1
J 0
(-3100 5600);
DISPLAY 0.680851 (-3100 5600);
DISPLAY INVISIBLE (-3100 5600);
FORCEPROP 1 LASTPIN (-3325 5575) $PN 1
J 0
(-3313 5587);
DISPLAY 0.510638 (-3313 5587);
PAINT MONO (-3313 5587);
FORCEPROP 1 LASTPIN (-3125 5575) $PN 2
J 0
(-3163 5587);
DISPLAY 0.510638 (-3163 5587);
PAINT MONO (-3163 5587);
FORCEPROP 1 LAST VALUE 33
J 2
(-3350 5575);
DISPLAY 0.489362 (-3350 5575);
PAINT SKYBLUE (-3350 5575);
FORCEPROP 2 LAST CDS_LIB pure_quanta
J 0
(-3225 5575);
DISPLAY INVISIBLE (-3225 5575);
FORCEPROP 1 LAST PATH I842
J 0
(-3275 5725);
DISPLAY 0.978723 (-3275 5725);
PAINT WHITE (-3275 5725);
DISPLAY INVISIBLE (-3275 5725);
FORCEPROP 2 LAST ROOM RST_CPU0_PLD_TO_DIMM
J 2
(-3200 5675);
DISPLAY 0.744681 (-3200 5675);
PAINT RED (-3200 5675);
DISPLAY INVISIBLE (-3200 5675);
FORCEPROP 1 LAST PACK_TYPE 0402LF
J 2
(-3050 5500);
DISPLAY 0.489362 (-3050 5500);
PAINT SKYBLUE (-3050 5500);
DISPLAY INVISIBLE (-3050 5500);
FORCEPROP 1 LAST PART_NUMBER CS03302JB29
J 2
(-3125 5625);
DISPLAY 0.489362 (-3125 5625);
PAINT SKYBLUE (-3125 5625);
DISPLAY INVISIBLE (-3125 5625);
FORCEPROP 1 LAST TOLERANCE 5%
J 0
(-3350 5550);
DISPLAY 0.489362 (-3350 5550);
PAINT SKYBLUE (-3350 5550);
DISPLAY INVISIBLE (-3350 5550);
FORCEPROP 1 LAST MATERIAL CHIP
J 2
(-3050 5550);
DISPLAY 0.489362 (-3050 5550);
PAINT SKYBLUE (-3050 5550);
DISPLAY INVISIBLE (-3050 5550);
FORCEPROP 1 LAST WATTAGE 1/16W
J 2
(-3300 5500);
DISPLAY 0.489362 (-3300 5500);
PAINT SKYBLUE (-3300 5500);
DISPLAY INVISIBLE (-3300 5500);
FORCEPROP 2 LAST BOM_COST MEM
J 2
(-3200 5725);
DISPLAY 0.744681 (-3200 5725);
PAINT WHITE (-3200 5725);
DISPLAY INVISIBLE (-3200 5725);
FORCEADD OFFPAGE..2
(-2125 5575);
FORCEPROP 2 LAST $XR0 27 
J 0
(-1936 5575);
DISPLAY 0.638298 (-1936 5575);
PAINT MONO (-1936 5575);
FORCEPROP 2 LAST CDS_LIB standard
J 0
(-2125 5575);
DISPLAY INVISIBLE (-2125 5575);
FORCEPROP 2 LAST PATH I843
J 0
(-1950 5650);
DISPLAY 0.680851 (-1950 5650);
DISPLAY INVISIBLE (-1950 5650);
FORCEPROP 1 LAST COMMENT_BODY TRUE
J 0
(-2170 5480);
DISPLAY 0.872340 (-2170 5480);
PAINT GREEN (-2170 5480);
DISPLAY INVISIBLE (-2170 5480);
FORCEPROP 1 LAST OFFPAGE TRUE
J 0
(-1800 5450);
DISPLAY 0.872340 (-1800 5450);
PAINT GREEN (-1800 5450);
DISPLAY INVISIBLE (-1800 5450);
FORCEADD Q_RES..1
(-6425 6025);
FORCEPROP 1 LAST LOCATION R267
J 0
(-6300 6025);
DISPLAY 0.489362 (-6300 6025);
PAINT SKYBLUE (-6300 6025);
FORCEPROP 0 LAST $SEC 1
J 0
(-6300 6050);
DISPLAY 0.680851 (-6300 6050);
PAINT MONO (-6300 6050);
DISPLAY INVISIBLE (-6300 6050);
FORCEPROP 0 LAST CDS_SEC 1
J 0
(-6300 6050);
DISPLAY 0.680851 (-6300 6050);
DISPLAY INVISIBLE (-6300 6050);
FORCEPROP 1 LASTPIN (-6525 6025) $PN 1
J 0
(-6513 6037);
DISPLAY 0.510638 (-6513 6037);
PAINT MONO (-6513 6037);
FORCEPROP 1 LASTPIN (-6325 6025) $PN 2
J 0
(-6363 6037);
DISPLAY 0.510638 (-6363 6037);
PAINT MONO (-6363 6037);
FORCEPROP 1 LAST VALUE 33
J 2
(-6550 6025);
DISPLAY 0.489362 (-6550 6025);
PAINT SKYBLUE (-6550 6025);
FORCEPROP 2 LAST CDS_LIB pure_quanta
J 0
(-6425 6025);
DISPLAY INVISIBLE (-6425 6025);
FORCEPROP 1 LAST PATH I844
J 0
(-6475 6175);
DISPLAY 0.978723 (-6475 6175);
PAINT WHITE (-6475 6175);
DISPLAY INVISIBLE (-6475 6175);
FORCEPROP 2 LAST ROOM RST_CPU0_PLD_TO_DIMM
J 2
(-6400 6125);
DISPLAY 0.744681 (-6400 6125);
PAINT RED (-6400 6125);
DISPLAY INVISIBLE (-6400 6125);
FORCEPROP 1 LAST PACK_TYPE 0402LF
J 2
(-6250 5950);
DISPLAY 0.489362 (-6250 5950);
PAINT SKYBLUE (-6250 5950);
DISPLAY INVISIBLE (-6250 5950);
FORCEPROP 1 LAST PART_NUMBER CS03302JB29
J 2
(-6325 6075);
DISPLAY 0.489362 (-6325 6075);
PAINT SKYBLUE (-6325 6075);
DISPLAY INVISIBLE (-6325 6075);
FORCEPROP 1 LAST TOLERANCE 5%
J 0
(-6550 6000);
DISPLAY 0.489362 (-6550 6000);
PAINT SKYBLUE (-6550 6000);
DISPLAY INVISIBLE (-6550 6000);
FORCEPROP 1 LAST MATERIAL CHIP
J 2
(-6250 6000);
DISPLAY 0.489362 (-6250 6000);
PAINT SKYBLUE (-6250 6000);
DISPLAY INVISIBLE (-6250 6000);
FORCEPROP 1 LAST WATTAGE 1/16W
J 2
(-6500 5950);
DISPLAY 0.489362 (-6500 5950);
PAINT SKYBLUE (-6500 5950);
DISPLAY INVISIBLE (-6500 5950);
FORCEPROP 2 LAST BOM_COST MEM
J 2
(-6400 6175);
DISPLAY 0.744681 (-6400 6175);
PAINT WHITE (-6400 6175);
DISPLAY INVISIBLE (-6400 6175);
FORCEADD OFFPAGE..5
(-7275 6025);
FORCEPROP 2 LAST $XR0 54 
J 0
(-7529 6025);
DISPLAY 0.638298 (-7529 6025);
PAINT MONO (-7529 6025);
FORCEPROP 2 LAST CDS_LIB standard
J 0
(-7275 6025);
DISPLAY INVISIBLE (-7275 6025);
FORCEPROP 2 LAST PATH I845
J 0
(-7225 6100);
DISPLAY 0.680851 (-7225 6100);
DISPLAY INVISIBLE (-7225 6100);
FORCEPROP 1 LAST OFFPAGE TRUE
J 0
(-6950 5900);
DISPLAY 0.872340 (-6950 5900);
PAINT GREEN (-6950 5900);
DISPLAY INVISIBLE (-6950 5900);
FORCEPROP 1 LAST COMMENT_BODY TRUE
J 0
(-7175 5950);
DISPLAY 0.872340 (-7175 5950);
PAINT GREEN (-7175 5950);
DISPLAY INVISIBLE (-7175 5950);
FORCEADD OFFPAGE..2
(-2300 4725);
FORCEPROP 2 LAST $XR0 158 
J 0
(-2111 4725);
DISPLAY 0.638298 (-2111 4725);
PAINT MONO (-2111 4725);
FORCEPROP 2 LAST CDS_LIB standard
J 0
(-2300 4725);
DISPLAY INVISIBLE (-2300 4725);
FORCEPROP 2 LAST PATH I846
J 0
(-2125 4800);
DISPLAY 0.680851 (-2125 4800);
DISPLAY INVISIBLE (-2125 4800);
FORCEPROP 1 LAST OFFPAGE TRUE
J 0
(-1975 4600);
DISPLAY 0.872340 (-1975 4600);
PAINT GREEN (-1975 4600);
DISPLAY INVISIBLE (-1975 4600);
FORCEPROP 1 LAST COMMENT_BODY TRUE
J 0
(-2345 4630);
DISPLAY 0.872340 (-2345 4630);
PAINT GREEN (-2345 4630);
DISPLAY INVISIBLE (-2345 4630);
FORCEADD OFFPAGE..2
(-2300 4525);
FORCEPROP 2 LAST $XR0 84 
J 0
(-2111 4525);
DISPLAY 0.638298 (-2111 4525);
PAINT MONO (-2111 4525);
FORCEPROP 1 LAST COMMENT_BODY TRUE
J 0
(-2345 4430);
DISPLAY 0.872340 (-2345 4430);
PAINT GREEN (-2345 4430);
DISPLAY INVISIBLE (-2345 4430);
FORCEPROP 1 LAST OFFPAGE TRUE
J 0
(-1975 4400);
DISPLAY 0.872340 (-1975 4400);
PAINT GREEN (-1975 4400);
DISPLAY INVISIBLE (-1975 4400);
FORCEPROP 2 LAST PATH I847
J 0
(-2125 4600);
DISPLAY 0.680851 (-2125 4600);
DISPLAY INVISIBLE (-2125 4600);
FORCEPROP 2 LAST CDS_LIB standard
J 0
(-2300 4525);
DISPLAY INVISIBLE (-2300 4525);
FORCEADD OFFPAGE..5
(-7275 4675);
FORCEPROP 2 LAST $XR0 84 
J 0
(-7529 4675);
DISPLAY 0.638298 (-7529 4675);
PAINT MONO (-7529 4675);
FORCEPROP 2 LAST CDS_LIB standard
J 0
(-7275 4675);
DISPLAY INVISIBLE (-7275 4675);
FORCEPROP 2 LAST PATH I848
J 0
(-7225 4750);
DISPLAY 0.680851 (-7225 4750);
DISPLAY INVISIBLE (-7225 4750);
FORCEPROP 1 LAST OFFPAGE TRUE
J 0
(-6950 4550);
DISPLAY 0.872340 (-6950 4550);
PAINT GREEN (-6950 4550);
DISPLAY INVISIBLE (-6950 4550);
FORCEPROP 1 LAST COMMENT_BODY TRUE
J 0
(-7175 4600);
DISPLAY 0.872340 (-7175 4600);
PAINT GREEN (-7175 4600);
DISPLAY INVISIBLE (-7175 4600);
FORCEADD OFFPAGE..5
(-7275 4325);
FORCEPROP 2 LAST $XR0 84 
J 0
(-7529 4325);
DISPLAY 0.638298 (-7529 4325);
PAINT MONO (-7529 4325);
FORCEPROP 1 LAST COMMENT_BODY TRUE
J 0
(-7175 4250);
DISPLAY 0.872340 (-7175 4250);
PAINT GREEN (-7175 4250);
DISPLAY INVISIBLE (-7175 4250);
FORCEPROP 1 LAST OFFPAGE TRUE
J 0
(-6950 4200);
DISPLAY 0.872340 (-6950 4200);
PAINT GREEN (-6950 4200);
DISPLAY INVISIBLE (-6950 4200);
FORCEPROP 2 LAST PATH I849
J 0
(-7225 4400);
DISPLAY 0.680851 (-7225 4400);
DISPLAY INVISIBLE (-7225 4400);
FORCEPROP 2 LAST CDS_LIB standard
J 0
(-7275 4325);
DISPLAY INVISIBLE (-7275 4325);
FORCEADD QUANTA_TITLE_BLOCK_C..1
(0 0);
FORCEPROP 0 LAST CDS_CON_LAST_MODIFIED Fri Mar 11 14:53:18 2022
J 0
(-1885 15);
DISPLAY INVISIBLE (-1885 15);
FORCEPROP 1 LAST CUSTOM_TXT_CDS <CON_LAST_MODIFIED>
J 0
(-1885 15);
DISPLAY 0.978723 (-1885 15);
FORCEPROP 2 LAST CUSTOM_TXT_CDS <XR_PAGE_TITLE>
J 0
(-7890 5250);
DISPLAY 0.638298 (-7890 5250);
PAINT PINK (-7890 5250);
DISPLAY INVISIBLE (-7890 5250);
FORCEPROP 1 LAST CUSTOM_TXT_CDS <NAME_2>
J 0
(-3175 50);
FORCEPROP 1 LAST CUSTOM_TXT_CDS <NAME_1>
J 0
(-3175 175);
FORCEPROP 1 LAST CUSTOM_TXT_CDS <Q_NUMBER>
J 0
(-1403 103);
DISPLAY 1.212766 (-1403 103);
FORCEPROP 1 LAST CUSTOM_TXT_CDS <Q_PROJ>
J 0
(-2382 102);
DISPLAY 1.212766 (-2382 102);
FORCEPROP 1 LAST CUSTOM_TXT_CDS <Q_REV>
J 0
(-184 103);
DISPLAY 1.212766 (-184 103);
FORCEPROP 1 LAST CUSTOM_TXT_CDS <CON_PAGE_NUM> OF <CON_TOTAL_PAGES>
J 0
(-446 18);
DISPLAY 0.978723 (-446 18);
FORCEPROP 1 LAST Q_TITLE FPGA 3/6
J 0
(-9300 50);
DISPLAY 2.446809 (-9300 50);
PAINT GREEN (-9300 50);
FORCEPROP 1 LAST Q_DEPT BU9
J 1
(-3763 49);
DISPLAY 1.957447 (-3763 49);
PAINT GREEN (-3763 49);
FORCEPROP 1 LAST COMMENT_BODY TRUE
J 0
(12 -13);
DISPLAY 0.978723 (12 -13);
PAINT GREEN (12 -13);
DISPLAY INVISIBLE (12 -13);
FORCEPROP 2 LAST PAGE_BORDER TRUE
J 0
(-7890 5250);
DISPLAY 0.638298 (-7890 5250);
PAINT PINK (-7890 5250);
DISPLAY INVISIBLE (-7890 5250);
FORCEPROP 1 LAST CDS_LMAN_SYM_OUTLINE -9475,6775,100,-125
J 0
(0 0);
DISPLAY 0.468085 (0 0);
PAINT GREEN (0 0);
DISPLAY INVISIBLE (0 0);
FORCEPROP 2 LAST CDS_LIB pure_quanta
J 0
(0 0);
DISPLAY INVISIBLE (0 0);
FORCEPROP 2 LAST CDS_XR_PAGE_TITLE CR-81 : @T6G_MB_LIB.T6G(SCH_1):PAGE81
J 0
(-7890 5250);
DISPLAY 0.638298 (-7890 5250);
PAINT PINK (-7890 5250);
DISPLAY INVISIBLE (-7890 5250);
WIRE 16 -1 (-7225 4375)(-6525 4375);
FORCEPROP 2 LAST SIG_NAME CPU0_CORETYPE1
J 0
(-7125 4385);
DISPLAY 0.489362 (-7125 4385);
WIRE 16 -1 (-5475 4325)(-7225 4325);
FORCEPROP 2 LAST SIG_NAME FM_SMB_RST_E1S_4_N
J 0
(-6160 4335);
DISPLAY 0.446809 (-6160 4335);
WIRE 16 -1 (-5475 4275)(-6325 4275);
FORCEPROP 2 LAST SIG_NAME FM_CPU0_SP5R2
J 0
(-6150 4285);
DISPLAY 0.489362 (-6150 4285);
FORCEPROP 2 LASTPROP $XRERR UNIQUE?
J 0
(-6390 4285);
DISPLAY 0.638298 (-6390 4285);
PAINT MONO (-6390 4285);
DISPLAY INVISIBLE (-6390 4285);
WIRE 16 -1 (-5475 4225)(-6325 4225);
FORCEPROP 2 LAST SIG_NAME FM_CPU0_SP5R1
J 0
(-6150 4235);
DISPLAY 0.489362 (-6150 4235);
FORCEPROP 2 LASTPROP $XRERR UNIQUE?
J 0
(-6390 4235);
DISPLAY 0.638298 (-6390 4235);
PAINT MONO (-6390 4235);
DISPLAY INVISIBLE (-6390 4235);
WIRE 16 -1 (-6325 4175)(-5475 4175);
FORCEPROP 2 LAST SIG_NAME FM_CPU1_CORETYPE0
J 0
(-6150 4185);
DISPLAY 0.489362 (-6150 4185);
FORCEPROP 2 LASTPROP $XRERR UNIQUE?
J 0
(-6390 4185);
DISPLAY 0.638298 (-6390 4185);
PAINT MONO (-6390 4185);
DISPLAY INVISIBLE (-6390 4185);
WIRE 16 -1 (-7225 4075)(-5475 4075);
FORCEPROP 2 LAST SIG_NAME PVDD11_S3_P0_PMALERT
J 0
(-7125 4085);
DISPLAY 0.489362 (-7125 4085);
WIRE 16 -1 (-5475 4025)(-6325 4025);
FORCEPROP 2 LAST SIG_NAME PRSNT_SLOT3_R_N
J 0
(-6150 4035);
DISPLAY 0.489362 (-6150 4035);
FORCEPROP 2 LASTPROP $XRERR UNIQUE?
J 0
(-6390 4035);
DISPLAY 0.638298 (-6390 4035);
PAINT MONO (-6390 4035);
DISPLAY INVISIBLE (-6390 4035);
WIRE 16 -1 (-5475 3975)(-7225 3975);
FORCEPROP 2 LAST SIG_NAME SLOT1_SKU_ID0
J 0
(-7125 3985);
DISPLAY 0.489362 (-7125 3985);
WIRE 16 -1 (-5475 4675)(-7225 4675);
FORCEPROP 2 LAST SIG_NAME FM_SMB_RST_E1S_3_N
J 0
(-6160 4685);
DISPLAY 0.446809 (-6160 4685);
WIRE 16 -1 (-7225 4625)(-6525 4625);
FORCEPROP 2 LAST SIG_NAME CPU1_SP5R2
J 0
(-7125 4635);
DISPLAY 0.489362 (-7125 4635);
WIRE 16 -1 (-7225 4575)(-6525 4575);
FORCEPROP 2 LAST SIG_NAME CPU1_SP5R1
J 0
(-7125 4585);
DISPLAY 0.489362 (-7125 4585);
WIRE 16 -1 (-7225 4475)(-5475 4475);
FORCEPROP 0 LAST SIG_NAME PRSNT_N_E1S_3_R
J 0
(-7125 4485);
DISPLAY 0.489362 (-7125 4485);
WIRE 16 -1 (-7225 4425)(-6525 4425);
FORCEPROP 2 LAST SIG_NAME CPU1_CORETYPE1
J 0
(-7125 4435);
DISPLAY 0.489362 (-7125 4435);
WIRE 16 -1 (-6325 4375)(-5475 4375);
FORCEPROP 2 LAST SIG_NAME FM_CPU0_CORETYPE1
J 0
(-6150 4385);
DISPLAY 0.489362 (-6150 4385);
FORCEPROP 2 LASTPROP $XRERR UNIQUE?
J 0
(-6390 4385);
DISPLAY 0.638298 (-6390 4385);
PAINT MONO (-6390 4385);
DISPLAY INVISIBLE (-6390 4385);
WIRE 16 -1 (-6325 4425)(-5475 4425);
FORCEPROP 2 LAST SIG_NAME FM_CPU1_CORETYPE1
J 0
(-6150 4435);
DISPLAY 0.489362 (-6150 4435);
FORCEPROP 2 LASTPROP $XRERR UNIQUE?
J 0
(-6390 4435);
DISPLAY 0.638298 (-6390 4435);
PAINT MONO (-6390 4435);
DISPLAY INVISIBLE (-6390 4435);
WIRE 16 -1 (-7225 4525)(-5475 4525);
FORCEPROP 0 LAST SIG_NAME PRSNT_N_E1S_4_R
J 0
(-7125 4535);
DISPLAY 0.489362 (-7125 4535);
WIRE 16 -1 (-7225 4725)(-6525 4725);
FORCEPROP 2 LAST SIG_NAME FM_PVDDCR_CPU1_P0_EN
J 0
(-7125 4735);
DISPLAY 0.489362 (-7125 4735);
WIRE 16 -1 (-6525 4825)(-7225 4825);
FORCEPROP 2 LAST SIG_NAME CPU0_SP5R3
J 0
(-7125 4835);
DISPLAY 0.489362 (-7125 4835);
WIRE 16 -1 (-6525 4925)(-7225 4925);
FORCEPROP 2 LAST SIG_NAME PWRGD_PVDDCR_CPU1_P0
J 0
(-7125 4935);
DISPLAY 0.489362 (-7125 4935);
WIRE 16 -1 (-5475 4875)(-7225 4875);
FORCEPROP 2 LAST SIG_NAME PWRGD_CHAF_CPU1
J 0
(-7125 4890);
DISPLAY 0.489362 (-7125 4890);
WIRE 16 -1 (-5475 4725)(-6325 4725);
FORCEPROP 2 LAST SIG_NAME FM_PVDDCR_CPU1_P0_R_EN
J 0
(-6150 4740);
DISPLAY 0.489362 (-6150 4740);
FORCEPROP 2 LASTPROP $XRERR UNIQUE?
J 0
(-6390 4740);
DISPLAY 0.638298 (-6390 4740);
PAINT MONO (-6390 4740);
DISPLAY INVISIBLE (-6390 4740);
WIRE 16 -1 (-6325 4625)(-5475 4625);
FORCEPROP 2 LAST SIG_NAME FM_CPU1_SP5R2
J 0
(-6150 4635);
DISPLAY 0.489362 (-6150 4635);
FORCEPROP 2 LASTPROP $XRERR UNIQUE?
J 0
(-6390 4635);
DISPLAY 0.638298 (-6390 4635);
PAINT MONO (-6390 4635);
DISPLAY INVISIBLE (-6390 4635);
WIRE 16 -1 (-6325 4575)(-5475 4575);
FORCEPROP 2 LAST SIG_NAME FM_CPU1_SP5R1
J 0
(-6150 4585);
DISPLAY 0.489362 (-6150 4585);
FORCEPROP 2 LASTPROP $XRERR UNIQUE?
J 0
(-6390 4585);
DISPLAY 0.638298 (-6390 4585);
PAINT MONO (-6390 4585);
DISPLAY INVISIBLE (-6390 4585);
WIRE 16 -1 (-7225 4775)(-6525 4775);
FORCEPROP 2 LAST SIG_NAME CPU1_CORETYPE2
J 0
(-7125 4785);
DISPLAY 0.489362 (-7125 4785);
WIRE 16 -1 (-7225 4275)(-6525 4275);
FORCEPROP 2 LAST SIG_NAME CPU0_SP5R2
J 0
(-7125 4285);
DISPLAY 0.489362 (-7125 4285);
WIRE 16 -1 (-2350 4025)(-4175 4025);
FORCEPROP 2 LAST SIG_NAME PVDD11_S3_P1_PMALERT
J 0
(-4050 4035);
DISPLAY 0.489362 (-4050 4035);
WIRE 16 -1 (-4175 4075)(-2350 4075);
FORCEPROP 2 LAST SIG_NAME PMDU_NODE_ID5
J 0
(-4060 4085);
DISPLAY 0.489362 (-4060 4085);
WIRE 16 -1 (-3275 4375)(-4175 4375);
FORCEPROP 2 LAST SIG_NAME FM_CPU0_SP5R4
J 0
(-4000 4385);
DISPLAY 0.489362 (-4000 4385);
FORCEPROP 2 LASTPROP $XRERR UNIQUE?
J 0
(-4240 4385);
DISPLAY 0.638298 (-4240 4385);
PAINT MONO (-4240 4385);
DISPLAY INVISIBLE (-4240 4385);
WIRE 16 -1 (-4175 4425)(-3275 4425);
FORCEPROP 2 LAST SIG_NAME FM_PRSNT_CPU0_R_N
J 0
(-4000 4425);
DISPLAY 0.489362 (-4000 4425);
FORCEPROP 2 LASTPROP $XRERR UNIQUE?
J 0
(-4240 4425);
DISPLAY 0.638298 (-4240 4425);
PAINT MONO (-4240 4425);
DISPLAY INVISIBLE (-4240 4425);
WIRE 16 -1 (-4175 4675)(-2350 4675);
FORCEPROP 0 LAST SIG_NAME PRSNT_N_E1S_2_R
J 0
(-4000 4685);
DISPLAY 0.489362 (-4000 4685);
WIRE 16 -1 (-4175 3975)(-3325 3975);
FORCEPROP 2 LAST SIG_NAME FM_PLD_OCP_AUX_PWR_R_EN
J 0
(-4050 3985);
DISPLAY 0.489362 (-4050 3985);
FORCEPROP 2 LASTPROP $XRERR UNIQUE?
J 0
(-4290 3985);
DISPLAY 0.638298 (-4290 3985);
PAINT MONO (-4290 3985);
DISPLAY INVISIBLE (-4290 3985);
WIRE 16 -1 (-2350 3925)(-4175 3925);
FORCEPROP 2 LAST SIG_NAME PVDDCR_CPU0_P1_PMALERT
J 0
(-4050 3935);
DISPLAY 0.489362 (-4050 3935);
WIRE 16 -1 (-2350 3875)(-4175 3875);
FORCEPROP 2 LAST SIG_NAME FM_CLKREQ_M2_1_N
J 0
(-4050 3885);
DISPLAY 0.489362 (-4050 3885);
WIRE 16 -1 (-4175 3725)(-2350 3725);
FORCEPROP 2 LAST SIG_NAME PWRGD_NIC_PWR_GOOD
J 0
(-4050 3735);
DISPLAY 0.489362 (-4050 3735);
WIRE 16 -1 (-3125 3775)(-2350 3775);
FORCEPROP 2 LAST SIG_NAME CLR_CMOS
J 0
(-2900 3785);
DISPLAY 0.489362 (-2900 3785);
WIRE 16 -1 (-2350 3825)(-4175 3825);
FORCEPROP 2 LAST SIG_NAME FM_CLKREQ_M2_2_N
J 0
(-4050 3835);
DISPLAY 0.489362 (-4050 3835);
WIRE 16 -1 (-3125 3975)(-2350 3975);
FORCEPROP 2 LAST SIG_NAME FM_PLD_OCP_AUX_PWR_EN
J 0
(-2900 3985);
DISPLAY 0.489362 (-2900 3985);
WIRE 16 -1 (-4175 4475)(-2350 4475);
FORCEPROP 0 LAST SIG_NAME PRSNT_N_E1S_1_R
J 0
(-4000 4485);
DISPLAY 0.489362 (-4000 4485);
WIRE 16 -1 (-4175 4525)(-2350 4525);
FORCEPROP 2 LAST SIG_NAME FM_SMB_RST_E1S_2_N
J 0
(-4010 4535);
DISPLAY 0.446809 (-4010 4535);
WIRE 16 -1 (-3075 4375)(-2350 4375);
FORCEPROP 2 LAST SIG_NAME CPU0_SP5R4
J 0
(-2900 4385);
DISPLAY 0.489362 (-2900 4385);
WIRE 16 -1 (-3075 4425)(-2350 4425);
FORCEPROP 2 LAST SIG_NAME FM_PRSNT_CPU0_N
J 0
(-2900 4435);
DISPLAY 0.489362 (-2900 4435);
WIRE 16 -1 (-2350 3675)(-4175 3675);
FORCEPROP 0 LAST SIG_NAME FM_SMB_RST_E1S_1_N
J 0
(-4060 3685);
DISPLAY 0.489362 (-4060 3685);
WIRE 16 -1 (-4175 4575)(-2350 4575);
FORCEPROP 2 LAST SIG_NAME PWRGD_CHAF_CPU0
J 0
(-4000 4590);
DISPLAY 0.489362 (-4000 4590);
WIRE 16 -1 (-3325 3775)(-4175 3775);
FORCEPROP 2 LAST SIG_NAME FM_CLR_CMOS
J 0
(-4050 3785);
DISPLAY 0.489362 (-4050 3785);
FORCEPROP 2 LASTPROP $XRERR UNIQUE?
J 0
(-4290 3785);
DISPLAY 0.638298 (-4290 3785);
PAINT MONO (-4290 3785);
DISPLAY INVISIBLE (-4290 3785);
WIRE 16 -1 (-4175 4625)(-2350 4625);
FORCEPROP 2 LAST SIG_NAME P12V_OCP_PWRGD
J 0
(-4000 4640);
DISPLAY 0.489362 (-4000 4640);
WIRE 16 -1 (-2350 4875)(-4175 4875);
FORCEPROP 2 LAST SIG_NAME PVDDCR_SOC_P0_EN
J 0
(-4000 4895);
DISPLAY 0.489362 (-4000 4895);
WIRE 16 -1 (-4175 4825)(-2350 4825);
FORCEPROP 2 LAST SIG_NAME PMDU_NODE_ID2
J 0
(-2900 4835);
DISPLAY 0.489362 (-2900 4835);
WIRE 16 -1 (-4175 4775)(-2350 4775);
FORCEPROP 2 LAST SIG_NAME PWRGD_CHGL_CPU0
J 0
(-4000 4790);
DISPLAY 0.489362 (-4000 4790);
WIRE 16 -1 (-4175 4725)(-2350 4725);
FORCEPROP 2 LAST SIG_NAME PSU2_PS_ON_N
J 0
(-2910 4735);
DISPLAY 0.446809 (-2910 4735);
WIRE 16 -1 (-3125 3575)(-2350 3575);
FORCEPROP 2 LAST SIG_NAME CPU0_CORETYPE2
J 0
(-2900 3585);
DISPLAY 0.489362 (-2900 3585);
WIRE 16 -1 (-3125 3625)(-2350 3625);
FORCEPROP 2 LAST SIG_NAME CPU0_CORETYPE0
J 0
(-2900 3635);
DISPLAY 0.489362 (-2900 3635);
WIRE 16 -1 (-3275 5125)(-4175 5125);
FORCEPROP 2 LAST SIG_NAME FM_PVDDCR_CPU1_P1_R_EN
J 0
(-4000 5130);
DISPLAY 0.489362 (-4000 5130);
FORCEPROP 2 LASTPROP $XRERR UNIQUE?
J 0
(-4240 5130);
DISPLAY 0.638298 (-4240 5130);
PAINT MONO (-4240 5130);
DISPLAY INVISIBLE (-4240 5130);
WIRE 16 -1 (-3275 5025)(-4175 5025);
FORCEPROP 2 LAST SIG_NAME FM_PVDD11_S3_P0_EN
J 0
(-4000 5030);
DISPLAY 0.489362 (-4000 5030);
FORCEPROP 2 LASTPROP $XRERR UNIQUE?
J 0
(-4240 5030);
DISPLAY 0.638298 (-4240 5030);
PAINT MONO (-4240 5030);
DISPLAY INVISIBLE (-4240 5030);
WIRE 16 -1 (-4175 4975)(-2350 4975);
FORCEPROP 2 LAST SIG_NAME PWRGD_PVDDCR_CPU0_P0
J 0
(-4000 4985);
DISPLAY 0.489362 (-4000 4985);
WIRE 16 -1 (-2350 4925)(-4175 4925);
FORCEPROP 2 LAST SIG_NAME PWRGD_PVDDCR_SOC_P0
J 0
(-4000 4940);
DISPLAY 0.489362 (-4000 4940);
WIRE 16 -1 (-7225 5775)(-6525 5775);
FORCEPROP 2 LAST SIG_NAME CPU0_XTRIG_L5
J 0
(-7125 5785);
DISPLAY 0.489362 (-7125 5785);
WIRE 16 -1 (-7225 5625)(-6525 5625);
FORCEPROP 2 LAST SIG_NAME CPU0_FPGA_SPARE_3
J 0
(-7125 5635);
DISPLAY 0.489362 (-7125 5635);
WIRE 16 -1 (-7225 5475)(-6525 5475);
FORCEPROP 2 LAST SIG_NAME CPU0_XTRIG_L7
J 0
(-7125 5485);
DISPLAY 0.489362 (-7125 5485);
WIRE 16 -1 (-6525 5375)(-7225 5375);
FORCEPROP 2 LAST SIG_NAME CPU1_FPGA_SPARE2
J 0
(-7125 5385);
DISPLAY 0.489362 (-7125 5385);
WIRE 16 -1 (-6525 5325)(-7225 5325);
FORCEPROP 2 LAST SIG_NAME PVDDCR_CPU0_P0_OCP_N
J 0
(-7125 5335);
DISPLAY 0.489362 (-7125 5335);
WIRE 16 -1 (-6525 5225)(-7225 5225);
FORCEPROP 2 LAST SIG_NAME PVDDCR_CPU1_P1_OCP_N
J 0
(-7125 5235);
DISPLAY 0.489362 (-7125 5235);
WIRE 16 -1 (-3325 6175)(-4175 6175);
FORCEPROP 2 LAST SIG_NAME FM_PVDDCR_CPU0_P1_OCP_N
J 0
(-4050 6185);
DISPLAY 0.489362 (-4050 6185);
FORCEPROP 2 LASTPROP $XRERR UNIQUE?
J 0
(-4290 6185);
DISPLAY 0.638298 (-4290 6185);
PAINT MONO (-4290 6185);
DISPLAY INVISIBLE (-4290 6185);
WIRE 16 -1 (-3325 6125)(-4175 6125);
FORCEPROP 2 LAST SIG_NAME FM_CPU1_PROCHOT_R_N
J 0
(-4050 6135);
DISPLAY 0.489362 (-4050 6135);
FORCEPROP 2 LASTPROP $XRERR UNIQUE?
J 0
(-4290 6135);
DISPLAY 0.638298 (-4290 6135);
PAINT MONO (-4290 6135);
DISPLAY INVISIBLE (-4290 6135);
WIRE 16 -1 (-3325 6075)(-4175 6075);
FORCEPROP 2 LAST SIG_NAME FM_PVDD11_S3_P1_OCP_N
J 0
(-4050 6085);
DISPLAY 0.489362 (-4050 6085);
FORCEPROP 2 LASTPROP $XRERR UNIQUE?
J 0
(-4290 6085);
DISPLAY 0.638298 (-4290 6085);
PAINT MONO (-4290 6085);
DISPLAY INVISIBLE (-4290 6085);
WIRE 16 -1 (-3325 6025)(-4175 6025);
FORCEPROP 2 LAST SIG_NAME FM_PVDD11_S3_P0_OCP_N
J 0
(-4050 6035);
DISPLAY 0.489362 (-4050 6035);
FORCEPROP 2 LASTPROP $XRERR UNIQUE?
J 0
(-4290 6035);
DISPLAY 0.638298 (-4290 6035);
PAINT MONO (-4290 6035);
DISPLAY INVISIBLE (-4290 6035);
WIRE 16 -1 (-6325 5625)(-5475 5625);
FORCEPROP 2 LAST SIG_NAME FM_CPU0_FPGA_SPARE_3
J 0
(-6150 5635);
DISPLAY 0.489362 (-6150 5635);
FORCEPROP 2 LASTPROP $XRERR UNIQUE?
J 0
(-6390 5635);
DISPLAY 0.638298 (-6390 5635);
PAINT MONO (-6390 5635);
DISPLAY INVISIBLE (-6390 5635);
WIRE 16 -1 (-4175 3525)(-3325 3525);
FORCEPROP 2 LAST SIG_NAME FM_PLD_OCP_MAIN_PWR_EN_R
J 0
(-4050 3535);
DISPLAY 0.489362 (-4050 3535);
FORCEPROP 2 LASTPROP $XRERR UNIQUE?
J 0
(-4290 3535);
DISPLAY 0.638298 (-4290 3535);
PAINT MONO (-4290 3535);
DISPLAY INVISIBLE (-4290 3535);
WIRE 16 -1 (-6525 4225)(-7225 4225);
FORCEPROP 2 LAST SIG_NAME CPU0_SP5R1
J 0
(-7125 4235);
DISPLAY 0.489362 (-7125 4235);
WIRE 16 -1 (-7225 4175)(-6525 4175);
FORCEPROP 2 LAST SIG_NAME CPU1_CORETYPE0
J 0
(-7125 4185);
DISPLAY 0.489362 (-7125 4185);
WIRE 16 -1 (-6525 5275)(-7225 5275);
FORCEPROP 2 LAST SIG_NAME PVDDCR_CPU1_P0_OCP_N
J 0
(-7125 5285);
DISPLAY 0.489362 (-7125 5285);
WIRE 16 -1 (-7225 3525)(-5475 3525);
FORCEPROP 2 LAST SIG_NAME PMDU_NODE_ID4
J 0
(-7125 3535);
DISPLAY 0.489362 (-7125 3535);
WIRE 16 -1 (-7225 3575)(-5475 3575);
FORCEPROP 2 LAST SIG_NAME PMDU_NODE_ID3
J 0
(-7125 3585);
DISPLAY 0.489362 (-7125 3585);
WIRE 16 -1 (-6525 4025)(-7225 4025);
FORCEPROP 2 LAST SIG_NAME PRSNT_SLOT3_N
J 0
(-7125 4035);
DISPLAY 0.489362 (-7125 4035);
WIRE 16 -1 (-4175 3625)(-3325 3625);
FORCEPROP 2 LAST SIG_NAME FM_CPU0_CORETYPE0
J 0
(-4050 3635);
DISPLAY 0.489362 (-4050 3635);
FORCEPROP 2 LASTPROP $XRERR UNIQUE?
J 0
(-4290 3635);
DISPLAY 0.638298 (-4290 3635);
PAINT MONO (-4290 3635);
DISPLAY INVISIBLE (-4290 3635);
WIRE 16 -1 (-4175 3575)(-3325 3575);
FORCEPROP 2 LAST SIG_NAME FM_CPU0_CORETYPE2
J 0
(-4050 3585);
DISPLAY 0.489362 (-4050 3585);
FORCEPROP 2 LASTPROP $XRERR UNIQUE?
J 0
(-4290 3585);
DISPLAY 0.638298 (-4290 3585);
PAINT MONO (-4290 3585);
DISPLAY INVISIBLE (-4290 3585);
WIRE 16 -1 (-5475 3625)(-7225 3625);
FORCEPROP 2 LAST SIG_NAME SCM_PRSNT0_N
J 0
(-7125 3635);
DISPLAY 0.489362 (-7125 3635);
WIRE 16 -1 (-7225 3675)(-5475 3675);
FORCEPROP 2 LAST SIG_NAME PMDU_NODE_ID1
J 0
(-7125 3685);
DISPLAY 0.489362 (-7125 3685);
WIRE 16 -1 (-7225 3725)(-5475 3725);
FORCEPROP 2 LAST SIG_NAME PVDDCR_CPU1_P0_SMB_ALERT
J 0
(-7125 3735);
DISPLAY 0.489362 (-7125 3735);
WIRE 16 -1 (-7225 3775)(-5475 3775);
FORCEPROP 2 LAST SIG_NAME PVDDCR_CPU1_P1_SMB_ALERT
J 0
(-7125 3785);
DISPLAY 0.489362 (-7125 3785);
WIRE 16 -1 (-5475 3825)(-7225 3825);
FORCEPROP 2 LAST SIG_NAME SLOT2_SKU_ID0
J 0
(-7125 3835);
DISPLAY 0.489362 (-7125 3835);
WIRE 16 -1 (-5475 3875)(-7225 3875);
FORCEPROP 2 LAST SIG_NAME SLOT1_SKU_ID1
J 0
(-7125 3885);
DISPLAY 0.489362 (-7125 3885);
WIRE 16 -1 (-6325 4775)(-5475 4775);
FORCEPROP 2 LAST SIG_NAME FM_CPU1_CORETYPE2
J 0
(-6150 4785);
DISPLAY 0.489362 (-6150 4785);
FORCEPROP 2 LASTPROP $XRERR UNIQUE?
J 0
(-6390 4785);
DISPLAY 0.638298 (-6390 4785);
PAINT MONO (-6390 4785);
DISPLAY INVISIBLE (-6390 4785);
WIRE 16 -1 (-6325 4975)(-5475 4975);
FORCEPROP 2 LAST SIG_NAME FM_CPU1_SP5R3
J 0
(-6150 4985);
DISPLAY 0.489362 (-6150 4985);
FORCEPROP 2 LASTPROP $XRERR UNIQUE?
J 0
(-6390 4985);
DISPLAY 0.638298 (-6390 4985);
PAINT MONO (-6390 4985);
DISPLAY INVISIBLE (-6390 4985);
WIRE 16 -1 (-5475 4825)(-6325 4825);
FORCEPROP 2 LAST SIG_NAME FM_CPU0_SP5R3
J 0
(-6150 4835);
DISPLAY 0.489362 (-6150 4835);
FORCEPROP 2 LASTPROP $XRERR UNIQUE?
J 0
(-6390 4835);
DISPLAY 0.638298 (-6390 4835);
PAINT MONO (-6390 4835);
DISPLAY INVISIBLE (-6390 4835);
WIRE 16 -1 (-7225 4975)(-6525 4975);
FORCEPROP 2 LAST SIG_NAME CPU1_SP5R3
J 0
(-7125 4985);
DISPLAY 0.489362 (-7125 4985);
WIRE 16 -1 (-6525 5525)(-7225 5525);
FORCEPROP 2 LAST SIG_NAME CPU1_FPGA_SPARE3
J 0
(-7125 5535);
DISPLAY 0.489362 (-7125 5535);
WIRE 16 -1 (-6525 5825)(-7225 5825);
FORCEPROP 2 LAST SIG_NAME CPU1_FPGA_SPARE0
J 0
(-7125 5835);
DISPLAY 0.489362 (-7125 5835);
WIRE 16 -1 (-7225 5575)(-6525 5575);
FORCEPROP 2 LAST SIG_NAME CPU0_FPGA_SPARE_0
J 0
(-7125 5585);
DISPLAY 0.489362 (-7125 5585);
WIRE 16 -1 (-6525 5425)(-7225 5425);
FORCEPROP 2 LAST SIG_NAME CPU1_FPGA_SPARE1
J 0
(-7125 5435);
DISPLAY 0.489362 (-7125 5435);
WIRE 16 -1 (-7225 5025)(-6525 5025);
FORCEPROP 2 LAST SIG_NAME CPU1_SP5R4
J 0
(-7125 5035);
DISPLAY 0.489362 (-7125 5035);
WIRE 16 -1 (-7225 5875)(-6525 5875);
FORCEPROP 2 LAST SIG_NAME CPU1_XTRIG_L7
J 0
(-7125 5885);
DISPLAY 0.489362 (-7125 5885);
WIRE 16 -1 (-6325 5475)(-5475 5475);
FORCEPROP 2 LAST SIG_NAME FM_CPU0_XTRIG_L7
J 0
(-6150 5485);
DISPLAY 0.489362 (-6150 5485);
FORCEPROP 2 LASTPROP $XRERR UNIQUE?
J 0
(-6390 5485);
DISPLAY 0.638298 (-6390 5485);
PAINT MONO (-6390 5485);
DISPLAY INVISIBLE (-6390 5485);
WIRE 16 -1 (-5475 5425)(-6325 5425);
FORCEPROP 2 LAST SIG_NAME FM_CPU1_FPGA_SPARE1
J 0
(-6150 5435);
DISPLAY 0.489362 (-6150 5435);
FORCEPROP 2 LASTPROP $XRERR UNIQUE?
J 0
(-6390 5435);
DISPLAY 0.638298 (-6390 5435);
PAINT MONO (-6390 5435);
DISPLAY INVISIBLE (-6390 5435);
WIRE 16 -1 (-5475 4925)(-6325 4925);
FORCEPROP 2 LAST SIG_NAME FM_PWRGD_PVDDCR_CPU1_P0
J 0
(-6150 4945);
DISPLAY 0.489362 (-6150 4945);
FORCEPROP 2 LASTPROP $XRERR UNIQUE?
J 0
(-6390 4945);
DISPLAY 0.638298 (-6390 4945);
PAINT MONO (-6390 4945);
DISPLAY INVISIBLE (-6390 4945);
WIRE 16 -1 (-6325 5025)(-5475 5025);
FORCEPROP 2 LAST SIG_NAME FM_CPU1_SP5R4
J 0
(-6150 5035);
DISPLAY 0.489362 (-6150 5035);
FORCEPROP 2 LASTPROP $XRERR UNIQUE?
J 0
(-6390 5035);
DISPLAY 0.638298 (-6390 5035);
PAINT MONO (-6390 5035);
DISPLAY INVISIBLE (-6390 5035);
WIRE 16 -1 (-7225 5125)(-5475 5125);
FORCEPROP 2 LAST SIG_NAME PWRGD_CHGL_CPU1
J 0
(-7125 5140);
DISPLAY 0.489362 (-7125 5140);
WIRE 16 -1 (-5475 6175)(-6325 6175);
FORCEPROP 2 LAST SIG_NAME FM_CPU1_XTRIG_L4
J 0
(-6150 6185);
DISPLAY 0.489362 (-6150 6185);
FORCEPROP 2 LASTPROP $XRERR UNIQUE?
J 0
(-6390 6185);
DISPLAY 0.638298 (-6390 6185);
PAINT MONO (-6390 6185);
DISPLAY INVISIBLE (-6390 6185);
WIRE 16 -1 (-5475 6125)(-6325 6125);
FORCEPROP 2 LAST SIG_NAME FM_CPU1_XTRIG_L5
J 0
(-6150 6135);
DISPLAY 0.489362 (-6150 6135);
FORCEPROP 2 LASTPROP $XRERR UNIQUE?
J 0
(-6390 6135);
DISPLAY 0.638298 (-6390 6135);
PAINT MONO (-6390 6135);
DISPLAY INVISIBLE (-6390 6135);
WIRE 16 -1 (-7225 5925)(-6525 5925);
FORCEPROP 2 LAST SIG_NAME CPU0_FPGA_SPARE_1
J 0
(-7125 5935);
DISPLAY 0.489362 (-7125 5935);
WIRE 16 -1 (-7225 5975)(-6525 5975);
FORCEPROP 2 LAST SIG_NAME CPU0_XTRIG_L6
J 0
(-7125 5985);
DISPLAY 0.489362 (-7125 5985);
WIRE 16 -1 (-6325 5575)(-5475 5575);
FORCEPROP 2 LAST SIG_NAME FM_CPU0_FPGA_SPARE_0
J 0
(-6150 5585);
DISPLAY 0.489362 (-6150 5585);
FORCEPROP 2 LASTPROP $XRERR UNIQUE?
J 0
(-6390 5585);
DISPLAY 0.638298 (-6390 5585);
PAINT MONO (-6390 5585);
DISPLAY INVISIBLE (-6390 5585);
WIRE 16 -1 (-5475 5325)(-6325 5325);
FORCEPROP 2 LAST SIG_NAME FM_PVDDCR_CPU0_P0_OCP_N
J 0
(-6150 5335);
DISPLAY 0.489362 (-6150 5335);
FORCEPROP 2 LASTPROP $XRERR UNIQUE?
J 0
(-6390 5335);
DISPLAY 0.638298 (-6390 5335);
PAINT MONO (-6390 5335);
DISPLAY INVISIBLE (-6390 5335);
WIRE 16 -1 (-5475 5225)(-6325 5225);
FORCEPROP 2 LAST SIG_NAME FM_PVDDCR_CPU1_P1_OCP_N
J 0
(-6150 5235);
DISPLAY 0.489362 (-6150 5235);
FORCEPROP 2 LASTPROP $XRERR UNIQUE?
J 0
(-6390 5235);
DISPLAY 0.638298 (-6390 5235);
PAINT MONO (-6390 5235);
DISPLAY INVISIBLE (-6390 5235);
WIRE 16 -1 (-5475 5275)(-6325 5275);
FORCEPROP 2 LAST SIG_NAME FM_PVDDCR_CPU1_P0_OCP_N
J 0
(-6150 5285);
DISPLAY 0.489362 (-6150 5285);
FORCEPROP 2 LASTPROP $XRERR UNIQUE?
J 0
(-6390 5285);
DISPLAY 0.638298 (-6390 5285);
PAINT MONO (-6390 5285);
DISPLAY INVISIBLE (-6390 5285);
WIRE 16 -1 (-6325 5375)(-5475 5375);
FORCEPROP 2 LAST SIG_NAME FM_CPU1_FPGA_SPARE2
J 0
(-6150 5385);
DISPLAY 0.489362 (-6150 5385);
FORCEPROP 2 LASTPROP $XRERR UNIQUE?
J 0
(-6390 5385);
DISPLAY 0.638298 (-6390 5385);
PAINT MONO (-6390 5385);
DISPLAY INVISIBLE (-6390 5385);
WIRE 16 -1 (-5475 5525)(-6325 5525);
FORCEPROP 2 LAST SIG_NAME FM_CPU1_FPGA_SPARE3
J 0
(-6150 5535);
DISPLAY 0.489362 (-6150 5535);
FORCEPROP 2 LASTPROP $XRERR UNIQUE?
J 0
(-6390 5535);
DISPLAY 0.638298 (-6390 5535);
PAINT MONO (-6390 5535);
DISPLAY INVISIBLE (-6390 5535);
WIRE 16 -1 (-7225 6075)(-6525 6075);
FORCEPROP 2 LAST SIG_NAME CPU1_XTRIG_L6
J 0
(-7125 6085);
DISPLAY 0.489362 (-7125 6085);
WIRE 16 -1 (-6525 6125)(-7225 6125);
FORCEPROP 2 LAST SIG_NAME CPU1_XTRIG_L5
J 0
(-7125 6135);
DISPLAY 0.489362 (-7125 6135);
WIRE 16 -1 (-6525 6175)(-7225 6175);
FORCEPROP 2 LAST SIG_NAME CPU1_XTRIG_L4
J 0
(-7125 6185);
DISPLAY 0.489362 (-7125 6185);
WIRE 16 -1 (-6525 6025)(-7225 6025);
FORCEPROP 2 LAST SIG_NAME CPU1_SA1
J 0
(-7135 6035);
DISPLAY 0.489362 (-7135 6035);
WIRE 16 -1 (-7225 5725)(-6525 5725);
FORCEPROP 2 LAST SIG_NAME CPU0_XTRIG_L4
J 0
(-7125 5735);
DISPLAY 0.489362 (-7125 5735);
WIRE 16 -1 (-7225 5675)(-6525 5675);
FORCEPROP 2 LAST SIG_NAME CPU0_FPGA_SPARE_2
J 0
(-7125 5685);
DISPLAY 0.489362 (-7125 5685);
WIRE 16 -1 (-6325 5925)(-5475 5925);
FORCEPROP 2 LAST SIG_NAME FM_CPU0_FPGA_SPARE_1
J 0
(-6150 5935);
DISPLAY 0.489362 (-6150 5935);
FORCEPROP 2 LASTPROP $XRERR UNIQUE?
J 0
(-6390 5935);
DISPLAY 0.638298 (-6390 5935);
PAINT MONO (-6390 5935);
DISPLAY INVISIBLE (-6390 5935);
WIRE 16 -1 (-6325 5975)(-5475 5975);
FORCEPROP 2 LAST SIG_NAME FM_CPU0_XTRIG_L6
J 0
(-6150 5985);
DISPLAY 0.489362 (-6150 5985);
FORCEPROP 2 LASTPROP $XRERR UNIQUE?
J 0
(-6390 5985);
DISPLAY 0.638298 (-6390 5985);
PAINT MONO (-6390 5985);
DISPLAY INVISIBLE (-6390 5985);
WIRE 16 -1 (-5475 6025)(-6325 6025);
FORCEPROP 2 LAST SIG_NAME FM_CPU1_SA1
J 0
(-6160 6035);
DISPLAY 0.489362 (-6160 6035);
FORCEPROP 2 LASTPROP $XRERR UNIQUE?
J 0
(-6400 6035);
DISPLAY 0.638298 (-6400 6035);
PAINT MONO (-6400 6035);
DISPLAY INVISIBLE (-6400 6035);
WIRE 16 -1 (-6325 6075)(-5475 6075);
FORCEPROP 2 LAST SIG_NAME FM_CPU1_XTRIG_L6
J 0
(-6150 6085);
DISPLAY 0.489362 (-6150 6085);
FORCEPROP 2 LASTPROP $XRERR UNIQUE?
J 0
(-6390 6085);
DISPLAY 0.638298 (-6390 6085);
PAINT MONO (-6390 6085);
DISPLAY INVISIBLE (-6390 6085);
WIRE 16 -1 (-5475 5825)(-6325 5825);
FORCEPROP 2 LAST SIG_NAME FM_CPU1_FPGA_SPARE0
J 0
(-6150 5835);
DISPLAY 0.489362 (-6150 5835);
FORCEPROP 2 LASTPROP $XRERR UNIQUE?
J 0
(-6390 5835);
DISPLAY 0.638298 (-6390 5835);
PAINT MONO (-6390 5835);
DISPLAY INVISIBLE (-6390 5835);
WIRE 16 -1 (-6325 5875)(-5475 5875);
FORCEPROP 2 LAST SIG_NAME FM_CPU1_XTRIG_L7
J 0
(-6150 5885);
DISPLAY 0.489362 (-6150 5885);
FORCEPROP 2 LASTPROP $XRERR UNIQUE?
J 0
(-6390 5885);
DISPLAY 0.638298 (-6390 5885);
PAINT MONO (-6390 5885);
DISPLAY INVISIBLE (-6390 5885);
WIRE 16 -1 (-6325 5775)(-5475 5775);
FORCEPROP 2 LAST SIG_NAME FM_CPU0_XTRIG_L5
J 0
(-6150 5785);
DISPLAY 0.489362 (-6150 5785);
FORCEPROP 2 LASTPROP $XRERR UNIQUE?
J 0
(-6390 5785);
DISPLAY 0.638298 (-6390 5785);
PAINT MONO (-6390 5785);
DISPLAY INVISIBLE (-6390 5785);
WIRE 16 -1 (-6325 5725)(-5475 5725);
FORCEPROP 2 LAST SIG_NAME FM_CPU0_XTRIG_L4
J 0
(-6150 5735);
DISPLAY 0.489362 (-6150 5735);
FORCEPROP 2 LASTPROP $XRERR UNIQUE?
J 0
(-6390 5735);
DISPLAY 0.638298 (-6390 5735);
PAINT MONO (-6390 5735);
DISPLAY INVISIBLE (-6390 5735);
WIRE 16 -1 (-6325 5675)(-5475 5675);
FORCEPROP 2 LAST SIG_NAME FM_CPU0_FPGA_SPARE_2
J 0
(-6150 5685);
DISPLAY 0.489362 (-6150 5685);
FORCEPROP 2 LASTPROP $XRERR UNIQUE?
J 0
(-6390 5685);
DISPLAY 0.638298 (-6390 5685);
PAINT MONO (-6390 5685);
DISPLAY INVISIBLE (-6390 5685);
WIRE 16 -1 (-4175 5775)(-3325 5775);
FORCEPROP 2 LAST SIG_NAME FM_CPU0_SA0
J 0
(-4060 5785);
DISPLAY 0.489362 (-4060 5785);
FORCEPROP 2 LASTPROP $XRERR UNIQUE?
J 0
(-4300 5785);
DISPLAY 0.638298 (-4300 5785);
PAINT MONO (-4300 5785);
DISPLAY INVISIBLE (-4300 5785);
WIRE 16 -1 (-3125 5575)(-2175 5575);
FORCEPROP 2 LAST SIG_NAME CPU0_SA1
J 0
(-2935 5585);
DISPLAY 0.489362 (-2935 5585);
WIRE 16 -1 (-2175 6025)(-3125 6025);
FORCEPROP 2 LAST SIG_NAME PVDD11_S3_P0_OCP_N
J 0
(-2925 6035);
DISPLAY 0.489362 (-2925 6035);
WIRE 16 -1 (-6175 450)(-6175 400);
WIRE 16 -1 (-6175 450)(-6175 500);
WIRE 16 -1 (-6175 450)(-6375 450);
WIRE 16 -1 (-6175 400)(-6175 350);
WIRE 16 -1 (-6175 400)(-6375 400);
WIRE 16 -1 (-6175 500)(-6175 550);
WIRE 16 -1 (-6175 500)(-6375 500);
WIRE 16 -1 (-6175 600)(-6175 550);
WIRE 16 -1 (-6175 550)(-6375 550);
WIRE 16 -1 (-6175 650)(-6175 600);
WIRE 16 -1 (-6175 600)(-6375 600);
WIRE 16 -1 (-6175 700)(-6175 650);
WIRE 16 -1 (-6175 650)(-6375 650);
WIRE 16 -1 (-6175 750)(-6175 700);
WIRE 16 -1 (-6175 700)(-6375 700);
WIRE 16 -1 (-6175 800)(-6175 750);
WIRE 16 -1 (-6175 750)(-6375 750);
WIRE 16 -1 (-6175 850)(-6175 800);
WIRE 16 -1 (-6175 800)(-6375 800);
WIRE 16 -1 (-6175 900)(-6175 850);
WIRE 16 -1 (-6175 850)(-6375 850);
WIRE 16 -1 (-6175 950)(-6175 900);
WIRE 16 -1 (-6175 900)(-6375 900);
WIRE 16 -1 (-6175 1000)(-6175 950);
WIRE 16 -1 (-6175 950)(-6375 950);
WIRE 16 -1 (-6175 1050)(-6175 1000);
WIRE 16 -1 (-6175 1000)(-6375 1000);
WIRE 16 -1 (-6175 1100)(-6175 1050);
WIRE 16 -1 (-6175 1050)(-6375 1050);
WIRE 16 -1 (-6175 1150)(-6175 1100);
WIRE 16 -1 (-6175 1100)(-6375 1100);
WIRE 16 -1 (-6175 1200)(-6175 1150);
WIRE 16 -1 (-6175 1150)(-6375 1150);
WIRE 16 -1 (-6175 1250)(-6175 1200);
WIRE 16 -1 (-6175 1200)(-6375 1200);
WIRE 16 -1 (-6175 1300)(-6175 1250);
WIRE 16 -1 (-6175 1250)(-6375 1250);
WIRE 16 -1 (-6175 1350)(-6175 1300);
WIRE 16 -1 (-6175 1300)(-6375 1300);
WIRE 16 -1 (-6175 1350)(-6175 1400);
WIRE 16 -1 (-6175 1350)(-6375 1350);
WIRE 16 -1 (-6175 1400)(-6175 1450);
WIRE 16 -1 (-6175 1400)(-6375 1400);
WIRE 16 -1 (-6175 1500)(-6175 1450);
WIRE 16 -1 (-6175 1450)(-6375 1450);
WIRE 16 -1 (-6175 1550)(-6175 1500);
WIRE 16 -1 (-6175 1500)(-6375 1500);
WIRE 16 -1 (-6175 1600)(-6175 1550);
WIRE 16 -1 (-6175 1550)(-6375 1550);
WIRE 16 -1 (-6175 1650)(-6175 1600);
WIRE 16 -1 (-6175 1600)(-6375 1600);
WIRE 16 -1 (-6175 1700)(-6175 1650);
WIRE 16 -1 (-6175 1650)(-6375 1650);
WIRE 16 -1 (-6175 1750)(-6175 1700);
WIRE 16 -1 (-6175 1700)(-6375 1700);
WIRE 16 -1 (-6175 1800)(-6175 1750);
WIRE 16 -1 (-6175 1750)(-6375 1750);
WIRE 16 -1 (-6175 1850)(-6175 1800);
WIRE 16 -1 (-6175 1800)(-6375 1800);
WIRE 16 -1 (-6175 1900)(-6175 1850);
WIRE 16 -1 (-6175 1850)(-6375 1850);
WIRE 16 -1 (-6175 1950)(-6175 1900);
WIRE 16 -1 (-6175 1900)(-6375 1900);
WIRE 16 -1 (-6175 2000)(-6175 1950);
WIRE 16 -1 (-6175 1950)(-6375 1950);
WIRE 16 -1 (-6175 2050)(-6175 2000);
WIRE 16 -1 (-6175 2000)(-6375 2000);
WIRE 16 -1 (-6175 2100)(-6175 2050);
WIRE 16 -1 (-6175 2050)(-6375 2050);
WIRE 16 -1 (-6175 2150)(-6175 2100);
WIRE 16 -1 (-6175 2100)(-6375 2100);
WIRE 16 -1 (-6175 2200)(-6175 2150);
WIRE 16 -1 (-6175 2150)(-6375 2150);
WIRE 16 -1 (-6175 2250)(-6175 2200);
WIRE 16 -1 (-6175 2200)(-6375 2200);
WIRE 16 -1 (-6175 2300)(-6175 2250);
WIRE 16 -1 (-6175 2250)(-6375 2250);
WIRE 16 -1 (-6175 2350)(-6175 2300);
WIRE 16 -1 (-6175 2300)(-6375 2300);
WIRE 16 -1 (-6175 2400)(-6175 2350);
WIRE 16 -1 (-6175 2350)(-6375 2350);
WIRE 16 -1 (-6175 2450)(-6175 2400);
WIRE 16 -1 (-6175 2400)(-6375 2400);
WIRE 16 -1 (-6175 2500)(-6175 2450);
WIRE 16 -1 (-6175 2450)(-6375 2450);
WIRE 16 -1 (-6175 2550)(-6175 2500);
WIRE 16 -1 (-6175 2500)(-6375 2500);
WIRE 16 -1 (-6175 2600)(-6175 2550);
WIRE 16 -1 (-6175 2550)(-6375 2550);
WIRE 16 -1 (-6175 2650)(-6175 2600);
WIRE 16 -1 (-6175 2600)(-6375 2600);
WIRE 16 -1 (-6175 2700)(-6175 2650);
WIRE 16 -1 (-6175 2650)(-6375 2650);
WIRE 16 -1 (-6175 2750)(-6175 2700);
WIRE 16 -1 (-6175 2700)(-6375 2700);
WIRE 16 -1 (-6175 2800)(-6175 2750);
WIRE 16 -1 (-6175 2750)(-6375 2750);
WIRE 16 -1 (-6175 2850)(-6175 2800);
WIRE 16 -1 (-6175 2800)(-6375 2800);
WIRE 16 -1 (-6175 2900)(-6175 2850);
WIRE 16 -1 (-6175 2850)(-6375 2850);
WIRE 16 -1 (-6175 2950)(-6175 2900);
WIRE 16 -1 (-6175 2900)(-6375 2900);
WIRE 16 -1 (-6175 2950)(-6375 2950);
WIRE 16 -1 (-2850 1625)(-3650 1625);
FORCEPROP 0 LAST VOLTAGE 3.3
J 0
(-3150 1625);
PAINT SKYBLUE (-3150 1625);
DISPLAY INVISIBLE (-3150 1625);
WIRE 16 -1 (-3650 1625)(-3650 1700);
WIRE 16 -1 (-3650 1575)(-3650 1625);
WIRE 16 -1 (-2850 1575)(-3650 1575);
FORCEPROP 0 LAST VOLTAGE 3.3
J 0
(-3150 1575);
PAINT SKYBLUE (-3150 1575);
DISPLAY INVISIBLE (-3150 1575);
WIRE 16 -1 (-3650 1525)(-3650 1575);
WIRE 16 -1 (-2850 1525)(-3650 1525);
FORCEPROP 0 LAST VOLTAGE 3.3
J 0
(-3150 1525);
PAINT SKYBLUE (-3150 1525);
DISPLAY INVISIBLE (-3150 1525);
WIRE 16 -1 (-3650 1325)(-3650 1525);
WIRE 16 -1 (-2850 1325)(-3650 1325);
FORCEPROP 0 LAST VOLTAGE 3.3
J 0
(-3150 1325);
PAINT SKYBLUE (-3150 1325);
DISPLAY INVISIBLE (-3150 1325);
WIRE 16 -1 (-3650 1275)(-3650 1325);
WIRE 16 -1 (-2850 1275)(-3650 1275);
FORCEPROP 0 LAST VOLTAGE 3.3
J 0
(-3150 1275);
PAINT SKYBLUE (-3150 1275);
DISPLAY INVISIBLE (-3150 1275);
WIRE 16 -1 (-3650 1225)(-3650 1275);
WIRE 16 -1 (-2850 1225)(-3650 1225);
FORCEPROP 0 LAST VOLTAGE 3.3
J 0
(-3150 1225);
PAINT SKYBLUE (-3150 1225);
DISPLAY INVISIBLE (-3150 1225);
WIRE 16 -1 (-3650 1125)(-3650 1225);
WIRE 16 -1 (-2850 1125)(-3650 1125);
WIRE 16 -1 (-3650 1125)(-3650 1075);
WIRE 16 -1 (-3650 1075)(-2850 1075);
WIRE 16 -1 (-3650 1075)(-3650 1025);
WIRE 16 -1 (-3650 1025)(-2850 1025);
WIRE 16 -1 (-3650 1025)(-3650 975);
WIRE 16 -1 (-3650 975)(-2850 975);
WIRE 16 -1 (-3650 975)(-3650 925);
WIRE 16 -1 (-3650 925)(-2850 925);
WIRE 16 -1 (-3650 925)(-3650 875);
WIRE 16 -1 (-3650 875)(-2850 875);
WIRE 16 -1 (-3650 875)(-3650 825);
WIRE 16 -1 (-3650 825)(-2850 825);
WIRE 16 -1 (-3650 825)(-3650 775);
WIRE 16 -1 (-3650 775)(-2850 775);
WIRE 16 -1 (-3650 775)(-3650 725);
WIRE 16 -1 (-3650 725)(-2850 725);
WIRE 16 -1 (-2850 2525)(-3150 2525);
WIRE 16 -1 (-3150 2525)(-3150 2600);
WIRE 16 -1 (-3150 2475)(-3150 2525);
WIRE 16 -1 (-2850 2475)(-3150 2475);
WIRE 16 -1 (-3150 2425)(-3150 2475);
WIRE 16 -1 (-2850 2425)(-3150 2425);
WIRE 16 -1 (-3150 2375)(-3150 2425);
WIRE 16 -1 (-2850 2375)(-3150 2375);
WIRE 16 -1 (-3150 2325)(-3150 2375);
WIRE 16 -1 (-2850 2325)(-3150 2325);
WIRE 16 -1 (-3150 2275)(-3150 2325);
WIRE 16 -1 (-2850 2275)(-3150 2275);
WIRE 16 -1 (-3150 2225)(-3150 2275);
WIRE 16 -1 (-2850 2225)(-3150 2225);
WIRE 16 -1 (-3150 2175)(-3150 2225);
WIRE 16 -1 (-2850 2175)(-3150 2175);
WIRE 16 -1 (-3150 2125)(-3150 2175);
WIRE 16 -1 (-2850 2125)(-3150 2125);
WIRE 16 -1 (-3150 2075)(-3150 2125);
WIRE 16 -1 (-2850 2075)(-3150 2075);
WIRE 16 -1 (-3150 2025)(-3150 2075);
WIRE 16 -1 (-2850 2025)(-3150 2025);
WIRE 16 -1 (-3150 1975)(-3150 2025);
WIRE 16 -1 (-2850 1975)(-3150 1975);
WIRE 16 -1 (-3350 1850)(-3350 1825);
WIRE 16 -1 (-2850 1825)(-3350 1825);
WIRE 16 -1 (-3350 1825)(-3350 1775);
WIRE 16 -1 (-2850 1775)(-3350 1775);
WIRE 16 -1 (-3350 1775)(-3350 1725);
WIRE 16 -1 (-2850 1725)(-3350 1725);
WIRE 16 -1 (-1550 775)(-1550 725);
WIRE 16 -1 (-1550 825)(-1550 775);
WIRE 16 -1 (-1550 775)(-1750 775);
WIRE 16 -1 (-1550 725)(-1750 725);
WIRE 16 -1 (-1550 875)(-1550 825);
WIRE 16 -1 (-1550 825)(-1750 825);
WIRE 16 -1 (-1550 925)(-1550 875);
WIRE 16 -1 (-1550 875)(-1750 875);
WIRE 16 -1 (-1550 975)(-1550 925);
WIRE 16 -1 (-1550 925)(-1750 925);
WIRE 16 -1 (-1550 1025)(-1550 975);
WIRE 16 -1 (-1550 975)(-1750 975);
WIRE 16 -1 (-1550 1075)(-1550 1025);
WIRE 16 -1 (-1550 1025)(-1750 1025);
WIRE 16 -1 (-1550 1125)(-1550 1075);
WIRE 16 -1 (-1550 1075)(-1750 1075);
WIRE 16 -1 (-1550 1175)(-1550 1125);
WIRE 16 -1 (-1550 1125)(-1750 1125);
WIRE 16 -1 (-1525 1900)(-1525 1825);
WIRE 16 -1 (-1525 1825)(-1525 1775);
WIRE 16 -1 (-1525 1825)(-1750 1825);
WIRE 16 -1 (-1525 1775)(-1525 1725);
WIRE 16 -1 (-1525 1775)(-1750 1775);
WIRE 16 -1 (-1525 1725)(-1525 1675);
WIRE 16 -1 (-1525 1725)(-1750 1725);
WIRE 16 -1 (-1525 1675)(-1525 1625);
WIRE 16 -1 (-1525 1675)(-1750 1675);
WIRE 16 -1 (-1525 1625)(-1525 1575);
WIRE 16 -1 (-1525 1625)(-1750 1625);
WIRE 16 -1 (-1525 1575)(-1525 1525);
WIRE 16 -1 (-1525 1575)(-1750 1575);
WIRE 16 -1 (-1525 1525)(-1525 1475);
WIRE 16 -1 (-1525 1525)(-1750 1525);
WIRE 16 -1 (-1525 1475)(-1525 1425);
WIRE 16 -1 (-1525 1475)(-1750 1475);
WIRE 16 -1 (-1525 1425)(-1750 1425);
WIRE 16 -1 (-4175 5575)(-3325 5575);
FORCEPROP 2 LAST SIG_NAME FM_CPU0_SA1
J 0
(-4060 5585);
DISPLAY 0.489362 (-4060 5585);
FORCEPROP 2 LASTPROP $XRERR UNIQUE?
J 0
(-4300 5585);
DISPLAY 0.638298 (-4300 5585);
PAINT MONO (-4300 5585);
DISPLAY INVISIBLE (-4300 5585);
WIRE 16 -1 (-3325 5825)(-4175 5825);
FORCEPROP 2 LAST SIG_NAME FM_CPU0_PROCHOT_R_N
J 0
(-4050 5835);
DISPLAY 0.489362 (-4050 5835);
FORCEPROP 2 LASTPROP $XRERR UNIQUE?
J 0
(-4290 5835);
DISPLAY 0.638298 (-4290 5835);
PAINT MONO (-4290 5835);
DISPLAY INVISIBLE (-4290 5835);
WIRE 16 -1 (-4175 5875)(-3325 5875);
FORCEPROP 2 LAST SIG_NAME FM_CPU1_SA0
J 0
(-4060 5885);
DISPLAY 0.489362 (-4060 5885);
FORCEPROP 2 LASTPROP $XRERR UNIQUE?
J 0
(-4300 5885);
DISPLAY 0.638298 (-4300 5885);
PAINT MONO (-4300 5885);
DISPLAY INVISIBLE (-4300 5885);
WIRE 16 -1 (-4175 5975)(-2175 5975);
FORCEPROP 2 LAST SIG_NAME CPU0_THERMTRIP_R_N
J 0
(-2925 5985);
DISPLAY 0.489362 (-2925 5985);
WIRE 16 -1 (-2175 6125)(-3125 6125);
FORCEPROP 2 LAST SIG_NAME CPU1_PROCHOT_N
J 0
(-2925 6135);
DISPLAY 0.489362 (-2925 6135);
WIRE 16 -1 (-2175 6175)(-3125 6175);
FORCEPROP 2 LAST SIG_NAME PVDDCR_CPU0_P1_OCP_N
J 0
(-2925 6185);
DISPLAY 0.489362 (-2925 6185);
WIRE 16 -1 (-2175 6075)(-3125 6075);
FORCEPROP 2 LAST SIG_NAME PVDD11_S3_P1_OCP_N
J 0
(-2925 6085);
DISPLAY 0.489362 (-2925 6085);
WIRE 16 -1 (-3125 5875)(-2175 5875);
FORCEPROP 2 LAST SIG_NAME CPU1_SA0
J 0
(-2935 5885);
DISPLAY 0.489362 (-2935 5885);
WIRE 16 -1 (-2175 5825)(-3125 5825);
FORCEPROP 2 LAST SIG_NAME CPU0_PROCHOT_N
J 0
(-2925 5835);
DISPLAY 0.489362 (-2925 5835);
WIRE 16 -1 (-3125 5775)(-2175 5775);
FORCEPROP 2 LAST SIG_NAME CPU0_SA0
J 0
(-2935 5785);
DISPLAY 0.489362 (-2935 5785);
WIRE 16 -1 (-2175 5625)(-3125 5625);
FORCEPROP 2 LAST SIG_NAME FM_INT_CPU0_HP_UBM_N
J 0
(-2925 5635);
DISPLAY 0.489362 (-2925 5635);
WIRE 16 -1 (-3075 5075)(-2350 5075);
FORCEPROP 2 LAST SIG_NAME FM_PRSNT_CPU1_N
J 0
(-2900 5085);
DISPLAY 0.489362 (-2900 5085);
WIRE 16 -1 (-3075 5125)(-2350 5125);
FORCEPROP 2 LAST SIG_NAME FM_PVDDCR_CPU1_P1_EN
J 0
(-2900 5135);
DISPLAY 0.489362 (-2900 5135);
WIRE 16 -1 (-3125 3525)(-2350 3525);
FORCEPROP 2 LAST SIG_NAME FM_PLD_OCP_MAIN_PWR_EN
J 0
(-2900 3535);
DISPLAY 0.489362 (-2900 3535);
WIRE 16 -1 (-2350 5025)(-3075 5025);
FORCEPROP 2 LAST SIG_NAME PVDD11_S3_P0_EN
J 0
(-2900 5035);
DISPLAY 0.489362 (-2900 5035);
WIRE 16 -1 (-4175 5925)(-2175 5925);
FORCEPROP 2 LAST SIG_NAME SMB_P1V8_M2_1_ALERT_N
J 0
(-2925 5935);
DISPLAY 0.489362 (-2925 5935);
WIRE 16 -1 (-4175 5725)(-2175 5725);
FORCEPROP 2 LAST SIG_NAME CPU1_THERMTRIP_R_N
J 0
(-4050 5735);
DISPLAY 0.489362 (-4050 5735);
WIRE 16 -1 (-4175 5675)(-2175 5675);
FORCEPROP 2 LAST SIG_NAME SMB_P1V8_M2_2_ALERT_N
J 0
(-4050 5685);
DISPLAY 0.489362 (-4050 5685);
WIRE 16 -1 (-4175 5525)(-2150 5525);
FORCEPROP 2 LAST SIG_NAME HPM_BRD_REV_ID0
J 0
(-2925 5535);
DISPLAY 0.489362 (-2925 5535);
WIRE 16 -1 (-4175 5475)(-2150 5475);
FORCEPROP 2 LAST SIG_NAME HPM_BRD_REV_ID1
J 0
(-2925 5485);
DISPLAY 0.489362 (-2925 5485);
WIRE 16 -1 (-4175 5425)(-2150 5425);
FORCEPROP 2 LAST SIG_NAME HPM_BRD_REV_ID2
J 0
(-2925 5435);
DISPLAY 0.489362 (-2925 5435);
WIRE 16 -1 (-4175 5075)(-3275 5075);
FORCEPROP 2 LAST SIG_NAME FM_PRSNT_CPU1_R_N
J 0
(-4000 5075);
DISPLAY 0.489362 (-4000 5075);
FORCEPROP 2 LASTPROP $XRERR UNIQUE?
J 0
(-4240 5075);
DISPLAY 0.638298 (-4240 5075);
PAINT MONO (-4240 5075);
DISPLAY INVISIBLE (-4240 5075);
WIRE 16 -1 (-3325 5625)(-4175 5625);
FORCEPROP 2 LAST SIG_NAME FM_INT_CPU0_HP_UBM_R_N
J 0
(-4050 5635);
DISPLAY 0.489362 (-4050 5635);
FORCEPROP 2 LASTPROP $XRERR UNIQUE?
J 0
(-4290 5635);
DISPLAY 0.638298 (-4290 5635);
PAINT MONO (-4290 5635);
DISPLAY INVISIBLE (-4290 5635);
DOT 1 (-6175 400);
DOT 1 (-6175 450);
DOT 1 (-6175 500);
DOT 1 (-6175 600);
DOT 1 (-6175 650);
DOT 1 (-6175 700);
DOT 1 (-6175 750);
DOT 1 (-6175 850);
DOT 1 (-6175 800);
DOT 1 (-6175 900);
DOT 1 (-6175 950);
DOT 1 (-6175 1000);
DOT 1 (-6175 1050);
DOT 1 (-6175 1100);
DOT 1 (-6175 1150);
DOT 1 (-6175 1200);
DOT 1 (-6175 1250);
DOT 1 (-6175 1300);
DOT 1 (-6175 1350);
DOT 1 (-6175 1400);
DOT 1 (-6175 1450);
DOT 1 (-6175 1500);
DOT 1 (-6175 1600);
DOT 1 (-6175 1550);
DOT 1 (-6175 1650);
DOT 1 (-6175 1700);
DOT 1 (-6175 1750);
DOT 1 (-6175 1800);
DOT 1 (-6175 1850);
DOT 1 (-6175 1900);
DOT 1 (-6175 1950);
DOT 1 (-6175 2000);
DOT 1 (-6175 2050);
DOT 1 (-6175 2100);
DOT 1 (-6175 2150);
DOT 1 (-6175 2200);
DOT 1 (-6175 2250);
DOT 1 (-6175 2300);
DOT 1 (-6175 2400);
DOT 1 (-6175 2350);
DOT 1 (-6175 2450);
DOT 1 (-6175 2500);
DOT 1 (-6175 2550);
DOT 1 (-6175 2650);
DOT 1 (-6175 2600);
DOT 1 (-6175 2700);
DOT 1 (-6175 2750);
DOT 1 (-6175 2800);
DOT 1 (-6175 2900);
DOT 1 (-6175 2850);
DOT 1 (-6175 550);
DOT 1 (-3650 775);
DOT 1 (-3650 825);
DOT 1 (-3650 875);
DOT 1 (-3650 925);
DOT 1 (-3650 975);
DOT 1 (-3650 1025);
DOT 1 (-3650 1075);
DOT 1 (-3650 1225);
DOT 1 (-3650 1125);
DOT 1 (-3650 1325);
DOT 1 (-3650 1275);
DOT 1 (-3650 1525);
DOT 1 (-3650 1575);
DOT 1 (-3650 1625);
DOT 1 (-3350 1775);
DOT 1 (-3350 1825);
DOT 1 (-3150 2025);
DOT 1 (-3150 2075);
DOT 1 (-3150 2125);
DOT 1 (-3150 2175);
DOT 1 (-3150 2225);
DOT 1 (-3150 2275);
DOT 1 (-3150 2325);
DOT 1 (-3150 2375);
DOT 1 (-3150 2425);
DOT 1 (-3150 2475);
DOT 1 (-3150 2525);
DOT 1 (-1550 775);
DOT 1 (-1550 825);
DOT 1 (-1550 925);
DOT 1 (-1550 875);
DOT 1 (-1550 975);
DOT 1 (-1550 1025);
DOT 1 (-1550 1075);
DOT 1 (-1550 1125);
DOT 1 (-1525 1825);
DOT 1 (-1525 1775);
DOT 1 (-1525 1725);
DOT 1 (-1525 1675);
DOT 1 (-1525 1625);
DOT 1 (-1525 1525);
DOT 1 (-1525 1575);
DOT 1 (-1525 1475);
FORCENOTE
BANK4 P3V3_STBY
(-4000 4150) 0;
DISPLAY LEFT (-4000 4150);
DISPLAY 3.148936 (-4000 4150);
FORCENOTE
BANK3 P3V3_STBY
(-4000 5200) 0;
DISPLAY LEFT (-4000 5200);
DISPLAY 3.148936 (-4000 5200);
FORCENOTE
BANK5 P1V8_STBY
(-4075 6325) 0;
DISPLAY LEFT (-4075 6325);
DISPLAY 3.148936 (-4075 6325);
QUIT
